G04 ================== begin FILE IDENTIFICATION RECORD ==================*
G04 Layout Name:  9048_F0T_Management_Board_D_brd_V04_1213_1625.brd*
G04 Film Name:    in1*
G04 File Format:  Gerber RS274X*
G04 File Origin:  Cadence Allegro 17.2-S081*
G04 Origin Date:  Tue Dec 13 16:31:10 2022*
G04 *
G04 Layer:  DRAWING FORMAT/TITLE_BLOCK_A*
G04 Layer:  DRAWING FORMAT/TITLE_BLOCK*
G04 Layer:  VIA CLASS/IN1*
G04 Layer:  PIN/IN1*
G04 Layer:  MANUFACTURING/PHOTOPLOT_OUTLINE*
G04 Layer:  ETCH/IN1*
G04 Layer:  DRAWING FORMAT/TITLE_DATA_IN1*
G04 *
G04 Offset:    (0.00 0.00)*
G04 Mirror:    No*
G04 Mode:      Positive*
G04 Rotation:  0*
G04 FullContactRelief:  No*
G04 UndefLineWidth:     6.00*
G04 ================== end FILE IDENTIFICATION RECORD ====================*
%FSLAX25Y25*MOIN*%
%IR0*IPPOS*OFA0.00000B0.00000*MIA0B0*SFA1.00000B1.00000*%
%ADD11C,.02*%
%ADD13C,.044*%
%ADD14C,.0315*%
%ADD12C,.018*%
%ADD10C,.085*%
%ADD15C,.015*%
%ADD16C,.0041*%
%ADD17C,.006*%
%ADD18C,.0033*%
%ADD19C,.0034*%
%ADD20C,.0045*%
%ADD21C,.0046*%
%ADD22C,.03004*%
%ADD23C,.02604*%
%ADD24C,.05404*%
%ADD25C,.02804*%
G75*
%LPD*%
G75*
G36*
G01X331081Y468024D02*
X332262D01*
X332646Y467640D01*
Y451968D01*
G03X336614Y448000I3969J1D01*
G01X346457D01*
G02X352331Y442126I0J-5874D01*
G01Y336646D01*
X345472D01*
G03X341504Y332678I0J-3968D01*
G01Y322834D01*
G03X345472Y318866I3968J0D01*
G01X352331D01*
Y7874D01*
G02X346457Y2000I-5874J0D01*
G01X7874D01*
G02X2000Y7874I0J5874D01*
G01Y318866D01*
X8858D01*
G03X12827Y322835I0J3969D01*
G01Y332677D01*
G03X8858Y336646I-3969J0D01*
G01X2000D01*
Y442126D01*
G02X7874Y448000I5874J0D01*
G01X17717D01*
G03X21685Y451968I-1J3969D01*
G01Y467365D01*
X22132Y467812D01*
X23372D01*
X23682Y467502D01*
Y451968D01*
G02X17717Y446002I-5966J0D01*
G01X7874D01*
G03X3998Y442126I0J-3876D01*
G01Y338644D01*
X8858D01*
G02X14822Y332811I-1J-5967D01*
G01Y322700D01*
G02X13132Y318671I-5964J133D01*
G01X13021Y318560D01*
G02X8858Y316868I-4163J4275D01*
G01X3998D01*
Y309084D01*
G03X3996Y309028I1224J-72D01*
G01Y120534D01*
G03X3998Y120478I1226J16D01*
G01Y7874D01*
G03X7874Y3998I3876J0D01*
G01X250841D01*
X301602D01*
X346457D01*
G03X350334Y7874I0J3877D01*
G01Y316868D01*
X345472D01*
G02X339508Y322701I1J5966D01*
G01Y332811D01*
G02X345472Y338644I5965J-133D01*
G01X350334D01*
Y442126D01*
G03X346459Y446002I-3876J0D01*
G01X336614D01*
G02X330648Y451968I0J5966D01*
G01Y467591D01*
X331081Y468024D01*
G37*
G36*
G01X24472Y315972D02*
X28800D01*
G02X29199Y315557I-1J-400D01*
G03X29198Y315500I1501J-55D01*
G03X30700Y313998I1502J0D01*
G03X32197Y315378I0J1502D01*
G02X32594Y315732I397J-46D01*
G01X34861D01*
X35489Y315104D01*
G03X36314Y314762I825J824D01*
G01X38487D01*
X39140Y314109D01*
G02X38906Y313429I-283J-283D01*
G03X37537Y311933I133J-1496D01*
G03X38052Y310800I1502J-1D01*
G02X38062Y310185I-250J-312D01*
G03X37537Y309044I977J-1141D01*
G03X40541I1502J0D01*
G03X40026Y310177I-1502J1D01*
G02X39997Y310775I250J312D01*
G01X40041Y310814D01*
G03X40535Y311800I-1002J1119D01*
G02X41215Y312034I397J-49D01*
G01X43502Y309747D01*
Y301240D01*
G03X43844Y300415I1166J0D01*
G01X45883Y298376D01*
G03X46708Y298034I825J824D01*
G01X47844D01*
Y293744D01*
X47965Y293624D01*
Y278514D01*
G02X47288Y278226I-400J1D01*
G03X46220Y278672I-1068J-1056D01*
G03Y275668I0J-1502D01*
G03X47288Y276114I0J1502D01*
G02X47965Y275826I277J-289D01*
G01Y268085D01*
X45182Y265302D01*
Y233882D01*
X33900Y222600D01*
Y209200D01*
X46500Y196600D01*
Y190500D01*
X53778Y183222D01*
Y131068D01*
X53304Y130594D01*
X53194Y130680D01*
G03X52237Y131024I-957J-1159D01*
G03X51344Y130730I0J-1503D01*
G02X50722Y130980I-230J327D01*
G03X49236Y132260I-1486J-223D01*
G03X47734Y130758I0J-1502D01*
G03X48318Y129569I1502J0D01*
G02X48313Y128943I-251J-311D01*
G03X47734Y127758I923J-1185D01*
G03X47839Y127207I1502J1D01*
G02X47460Y126680I-380J-127D01*
G01X42512D01*
G02X42133Y127207I1J400D01*
G03X42228Y127582I-1396J553D01*
G01X42230Y127601D01*
G03X42238Y127758I-1494J155D01*
G03X41654Y128947I-1502J0D01*
G02X41659Y129573I251J311D01*
G03X42238Y130758I-923J1185D01*
G03X39234I-1502J0D01*
G03X39818Y129569I1502J0D01*
G02X39813Y128943I-251J-311D01*
G03X39234Y127758I923J-1185D01*
G03X39339Y127207I1502J1D01*
G02X38960Y126680I-380J-127D01*
G01X34012D01*
G02X33633Y127207I1J400D01*
G03X33728Y127582I-1396J553D01*
G01X33730Y127601D01*
G03X33738Y127758I-1494J155D01*
G03X33154Y128947I-1502J0D01*
G02X33159Y129573I251J311D01*
G03X33738Y130758I-923J1185D01*
G03X30734I-1502J0D01*
G03X31318Y129569I1502J0D01*
G02X31313Y128943I-251J-311D01*
G03X30734Y127758I923J-1185D01*
G03X30839Y127207I1502J1D01*
G02X30460Y126680I-380J-127D01*
G01X25512D01*
G02X25133Y127207I1J400D01*
G03X25228Y127582I-1396J553D01*
G01X25230Y127601D01*
G03X25238Y127758I-1494J155D01*
G03X24654Y128947I-1502J0D01*
G02X24659Y129573I251J311D01*
G03X25238Y130758I-923J1185D01*
G03X22234I-1502J0D01*
G03X22818Y129569I1502J0D01*
G02X22813Y128943I-251J-311D01*
G03X22234Y127758I923J-1185D01*
G03X22339Y127207I1502J1D01*
G02X21960Y126680I-380J-127D01*
G01X20381D01*
X15221Y131840D01*
Y189900D01*
X16521Y191200D01*
X19700D01*
X22900Y194400D01*
Y221200D01*
X23900Y222200D01*
Y229200D01*
X22900Y230200D01*
X16221D01*
X15221Y231200D01*
Y250921D01*
X18740Y254440D01*
Y259571D01*
X15221Y263090D01*
Y299665D01*
X15223Y299679D01*
G03X15238Y299884I-1487J212D01*
G01Y299891D01*
G03X15223Y300103I-1502J0D01*
G01X15221Y300117D01*
Y303054D01*
X15223Y303068D01*
G03X15238Y303273I-1487J212D01*
G01Y303280D01*
G03X15223Y303492I-1502J0D01*
G01X15221Y303506D01*
Y306721D01*
X20063Y311563D01*
G02X20735Y311369I282J-283D01*
G01X20751Y311264D01*
G03X21260Y310340I1486J217D01*
G01X21265Y310336D01*
G02X21260Y309733I-265J-299D01*
G03X20735Y308592I977J-1141D01*
G03X23739I1502J0D01*
G03X23224Y309725I-1502J1D01*
G02X23214Y310340I250J312D01*
G03X23739Y311481I-977J1141D01*
G03X22396Y312975I-1502J0D01*
G02X22155Y313655I42J398D01*
G01X24472Y315972D01*
G37*
G36*
G01X38828Y468024D02*
X40009D01*
X40382Y467651D01*
Y451968D01*
G03X44350Y448000I3969J1D01*
G01X45976D01*
X46336Y447640D01*
Y446364D01*
X45974Y446002D01*
X44350D01*
G02X38384Y451968I0J5966D01*
G01Y467580D01*
X38828Y468024D01*
G37*
G36*
G01X115900Y237600D02*
X120900Y232600D01*
X122900D01*
X124900Y230600D01*
Y227200D01*
X124390Y226690D01*
X124301Y226694D01*
G03X124226Y226696I-78J-1500D01*
G03X122792Y225641I0J-1502D01*
G01X122748Y225500D01*
X120495D01*
X118044Y227950D01*
G03X117837Y228120I-966J-966D01*
G01X116835Y228790D01*
G02X116865Y229473I223J332D01*
G03X117645Y230790I-722J1317D01*
G03X114641I-1502J0D01*
G03X114648Y230645I1502J0D01*
G01X114655Y230573D01*
X114504Y230348D01*
X114258Y230512D01*
G03X114022Y230639I-762J-1134D01*
G01X112895Y231105D01*
X112700Y231300D01*
X112425D01*
X109642Y232453D01*
G03X109119Y232556I-520J-1263D01*
G01X100732D01*
G03X100209Y232453I-3J-1366D01*
G01X97426Y231300D01*
X96300D01*
X95504Y230504D01*
X94682Y230164D01*
G03X94239Y229867I525J-1262D01*
G01X92838Y228466D01*
X88867D01*
G03X87901Y228066I0J-1366D01*
G01X86001Y226166D01*
X69400D01*
G03X68434Y225766I0J-1366D01*
G01X68167Y225500D01*
X62500D01*
X55700Y218700D01*
Y209766D01*
X55693Y209740D01*
G03X55639Y209341I1447J-399D01*
G01Y209324D01*
X55640Y209240D01*
X54000Y207600D01*
X51500D01*
X49600Y209500D01*
Y223600D01*
X60455Y234455D01*
X60486Y234470D01*
G03X61210Y235194I-636J1360D01*
G01X61225Y235225D01*
X61500Y235500D01*
X70553D01*
X70603Y235373D01*
G03X70658Y235250I1397J551D01*
G01X70679Y235160D01*
X70553Y234974D01*
G03X69598Y233575I547J-1399D01*
G03X72602I1502J0D01*
G03X72507Y234100I-1502J-1D01*
G02X72696Y234594I375J140D01*
G03X73397Y235373I-696J1331D01*
G01X73447Y235500D01*
X83000D01*
X83634Y236134D01*
X84745D01*
G03X84800Y236133I47J1066D01*
G03X85555Y236445I1J1067D01*
G01X85610Y236500D01*
X86229D01*
G03X88771I1271J800D01*
G01X97291D01*
X97343Y236380D01*
G03X100097I1377J600D01*
G01X100149Y236500D01*
X102378D01*
G03X103580Y235898I1202J899D01*
G03X105082Y237400I0J1502D01*
G02X105282Y237600I200J0D01*
G01X115900D01*
G37*
G36*
G01X61128Y314843D02*
G03I-567J0D01*
G37*
G36*
G01X74908Y157000D02*
X77500D01*
X86798Y147702D01*
Y143174D01*
X86688Y143063D01*
X86687Y143062D01*
G03X86619Y142988I751J-758D01*
G01X86586Y142948D01*
G03X86429Y142689I824J-677D01*
G01X86426Y142682D01*
G03X86345Y142368I980J-420D01*
G01X86344Y142358D01*
Y142357D01*
G03X86340Y142314I1060J-120D01*
G01Y142310D01*
X86339Y142297D01*
Y142295D01*
G03X86334Y142191I1061J-103D01*
G01Y134343D01*
G03X86341Y134222I1066J1D01*
G01X86346Y134179D01*
G03X86581Y133625I1059J122D01*
G01X86613Y133587D01*
X86614Y133586D01*
G03X86683Y133509I827J672D01*
G01X88213Y131979D01*
G03X88301Y131900I755J753D01*
G01X88336Y131872D01*
G03X88879Y131646I665J833D01*
G01X88922Y131641D01*
G03X89043Y131634I122J1059D01*
G01X89866D01*
X97000Y124500D01*
Y85478D01*
X94668Y83146D01*
X93230D01*
G02X92852Y83588I20J400D01*
G03X92860Y83745I-1494J155D01*
G03X92281Y84930I-1502J0D01*
G02Y85560I246J315D01*
G03Y87930I-923J1185D01*
G02Y88560I246J315D01*
G03Y90930I-923J1185D01*
G02Y91560I246J315D01*
G03X92860Y92745I-923J1185D01*
G03X89856I-1502J0D01*
G03X90435Y91560I1502J0D01*
G02Y90930I-246J-315D01*
G03Y88560I923J-1185D01*
G02Y87930I-246J-315D01*
G03Y85560I923J-1185D01*
G02Y84930I-246J-315D01*
G03X89856Y83745I923J-1185D01*
G03X89864Y83588I1502J-2D01*
G02X89486Y83146I-398J-42D01*
G01X76649D01*
G02X76251Y83588I0J400D01*
G03X76259Y83745I-1494J155D01*
G03X75680Y84930I-1502J0D01*
G02Y85560I246J315D01*
G03Y87930I-923J1185D01*
G02Y88560I246J315D01*
G03Y90930I-923J1185D01*
G02Y91560I246J315D01*
G03X76259Y92745I-923J1185D01*
G03X73255I-1502J0D01*
G03X73834Y91560I1502J0D01*
G02Y90930I-246J-315D01*
G03Y88560I923J-1185D01*
G02X73839Y87934I-246J-315D01*
G03X73255Y86745I918J-1189D01*
G03X73263Y86588I1502J-2D01*
G01X73265Y86569D01*
G03X73834Y85560I1492J176D01*
G02Y84930I-246J-315D01*
G03X73255Y83745I923J-1185D01*
G03X73263Y83588I1502J-2D01*
G02X72865Y83146I-398J-42D01*
G01X72744D01*
X64860Y91030D01*
Y108738D01*
X65757Y110903D01*
G03X65902Y111631I-1757J728D01*
G01Y112578D01*
X68626Y120527D01*
Y128032D01*
G03X68628Y128100I-1500J78D01*
G03X68626Y128168I-1502J-10D01*
G01Y136969D01*
X67316Y138279D01*
Y153816D01*
X67534Y154034D01*
X71457D01*
G03X71578Y154041I-1J1066D01*
G01X71621Y154046D01*
G03X72175Y154281I-122J1059D01*
G01X72213Y154313D01*
X72214Y154314D01*
G03X72291Y154383I-672J827D01*
G01X74908Y157000D01*
G37*
G36*
G01X89077Y313045D02*
X76413D01*
X74516Y311148D01*
Y297561D01*
X75182Y296895D01*
X85880D01*
X89385Y300400D01*
Y312737D01*
X89077Y313045D01*
G37*
G36*
G01X160070Y227154D02*
X160315Y227398D01*
X160534Y227180D01*
Y221876D01*
G03X160702Y221273I1166J0D01*
G03X161625Y219988I1498J102D01*
G01X161662Y219973D01*
X161775Y219860D01*
X163286D01*
X163725Y219421D01*
Y218105D01*
X163394Y217774D01*
X161003D01*
X157163Y213934D01*
X155616D01*
G02X155234Y214453I0J400D01*
G03X155302Y214900I-1435J447D01*
G03X154897Y215926I-1502J0D01*
G02X154885Y216459I292J273D01*
G03X155246Y217435I-1141J977D01*
G03X152242I-1502J0D01*
G03X152647Y216409I1502J0D01*
G02X152659Y215876I-292J-273D01*
G03X152306Y215059I1140J-977D01*
G02X151907Y214702I-398J43D01*
G01X151900D01*
G03X150590Y213934I0J-1501D01*
G01X139572D01*
X139526Y214071D01*
G03X136674I-1426J-471D01*
G01X136628Y213934D01*
X132566D01*
X131000Y215500D01*
Y222500D01*
X131818Y223318D01*
X132596D01*
X133333Y222581D01*
G03X134158Y222240I824J825D01*
G01X135624D01*
G03X136449Y222581I1J1166D01*
G01X137186Y223318D01*
X140796D01*
G03X143112I1158J955D01*
G01X145073D01*
G03X147707I1317J722D01*
G01X152772D01*
X156608Y227154D01*
X160070D01*
G37*
G36*
G01X160933Y242083D02*
X167707D01*
X171927Y237863D01*
X172235D01*
X172262Y237836D01*
X190240D01*
G02X190563Y237199I0J-400D01*
G03X190291Y236370I1130J-830D01*
G03X193095I1402J0D01*
G03X192552Y237478I-1402J0D01*
G01X192475Y237538D01*
Y237836D01*
X192914D01*
X194434Y236317D01*
Y233852D01*
G02X194048Y233452I-400J0D01*
G03Y230850I46J-1301D01*
G02X194434Y230450I-14J-400D01*
G01Y227553D01*
G02X194048Y227153I-400J0D01*
G03X192792Y225852I46J-1301D01*
G03X192794Y225787I1302J8D01*
G02X192394Y225366I-400J-21D01*
G01X189291D01*
X189272D01*
G02X189072Y225604I-3J200D01*
G03X189096Y225852I-1278J249D01*
G03X186492I-1302J0D01*
G03X186578Y225385I1302J-2D01*
G02X186276Y225151I-187J-71D01*
G03X186025Y225286I-674J-952D01*
G02X185905Y225523I73J186D01*
G03X185947Y225852I-1260J328D01*
G03X183343I-1302J0D01*
G03X183367Y225604I1302J1D01*
G01X183370Y225586D01*
Y225366D01*
X182770D01*
Y225586D01*
X182773Y225604D01*
G03X182797Y225852I-1278J249D01*
G03X180193I-1302J0D01*
G03X180217Y225604I1302J1D01*
G01X180220Y225586D01*
Y225366D01*
X179621D01*
Y225586D01*
X179624Y225604D01*
G03X179648Y225852I-1278J249D01*
G03X178346Y227154I-1302J0D01*
G03X177432Y226779I0J-1301D01*
G02X176868Y226781I-281J285D01*
G01X176125Y227524D01*
G02X176123Y228088I283J283D01*
G03X176498Y229002I-926J914D01*
G03X173894I-1302J0D01*
G03X173898Y228898I1302J-2D01*
G02X173499Y228466I-399J-32D01*
G01X168583D01*
X165225Y231825D01*
G03X164400Y232166I-824J-825D01*
G01X162700D01*
G03X162367Y232118I-2J-1166D01*
G02X162179Y232461I-57J192D01*
G03X162702Y233600I-979J1139D01*
G03X161200Y232098I-1502J0D01*
G03X161696Y232182I1J1502D01*
G02X161899Y231848I66J-189D01*
G03X161875Y231825I795J-854D01*
G01X160875Y230825D01*
G03X160534Y230000I825J-824D01*
G01Y229034D01*
X159655Y228155D01*
X148605D01*
X147430Y229330D01*
X144517D01*
G02X144138Y229858I0J400D01*
G03X144252Y230549I-2053J694D01*
G03X142463Y232682I-2166J0D01*
G03X141361Y232984I-1103J-1865D01*
G01X140614D01*
X140232Y233366D01*
G03X138700Y234000I-1531J-1532D01*
G01X129294D01*
Y237294D01*
X130000Y238000D01*
X137036D01*
X137070Y237987D01*
G03X137481Y237912I412J1092D01*
G01X146808D01*
X149545Y235175D01*
G03X150370Y234834I824J825D01*
G01X151587D01*
X151605Y234653D01*
G03X153100Y233298I1495J147D01*
G03X154127Y233704I0J1502D01*
G02X154695Y233683I274J-292D01*
G03X155800Y233198I1105J1016D01*
G03Y236202I0J1502D01*
G03X154773Y235796I0J-1502D01*
G02X154205Y235817I-274J292D01*
G03X153995Y236006I-1105J-1017D01*
G02X153950Y236610I238J321D01*
G01X154025Y236685D01*
G03X154366Y237510I-825J824D01*
G01Y238000D01*
X156717D01*
X157213Y238496D01*
X157289Y238501D01*
G03X158686Y239780I-89J1499D01*
G01X158696Y239846D01*
X160933Y242083D01*
G37*
G36*
G01X176700Y70700D02*
X194000D01*
X195500Y69200D01*
Y58500D01*
X193860Y56860D01*
G03X193821Y56822I934J-997D01*
G01X185300Y48302D01*
X153000D01*
X149000Y52302D01*
Y64200D01*
X151400Y66600D01*
X172600D01*
X176700Y70700D01*
G37*
G36*
G01X194141Y171085D02*
X198641D01*
X199085Y170641D01*
Y155775D01*
X184963Y141653D01*
G03X184000Y142002I-963J-1154D01*
G03X182498Y140500I0J-1502D01*
G03X182786Y139616I1501J0D01*
G01X180997Y137826D01*
X163158D01*
G03X162333Y137485I-1J-1166D01*
G01X160762Y135913D01*
G02X160168Y135945I-283J283D01*
G03X159000Y136502I-1168J-946D01*
G03X157498Y135000I0J-1502D01*
G03X157611Y134428I1502J0D01*
G02X157241Y133876I-370J-152D01*
G01X149974D01*
X147808Y136042D01*
Y142767D01*
X148611Y143570D01*
X154913D01*
X156470Y145127D01*
X171162D01*
G03X173038I938J1173D01*
G01X175097D01*
X182875Y152905D01*
G02X183507Y152816I282J-283D01*
G03X184645Y152147I1138J633D01*
G03X185947Y153449I0J1302D01*
G03X185278Y154587I-1302J0D01*
G02X185189Y155219I194J350D01*
G01X186024Y156054D01*
G02X186656Y155966I283J-283D01*
G03X187794Y155297I1138J633D01*
G03X189096Y156599I0J1302D01*
G03X188427Y157737I-1302J0D01*
G02X188339Y158369I195J349D01*
G01X189174Y159204D01*
G02X189806Y159115I282J-283D01*
G03X190944Y158446I1138J633D01*
G03X192246Y159748I0J1302D01*
G03X191577Y160886I-1302J0D01*
G02X191488Y161518I194J350D01*
G01X192324Y162354D01*
G02X192956Y162265I282J-283D01*
G03X194094Y161596I1138J633D01*
G03Y164200I0J1302D01*
G03X193647Y164121I0J-1302D01*
G02X193110Y164497I-137J376D01*
G01Y164766D01*
G02X193414Y164936I200J0D01*
G03X194094Y164745I679J1111D01*
G03Y167349I0J1302D01*
G03X193647Y167270I0J-1302D01*
G02X193110Y167646I-137J376D01*
G01Y170054D01*
X194141Y171085D01*
G37*
G36*
G01X192923Y185092D02*
X193089Y184926D01*
Y171608D01*
X192108Y170627D01*
Y170349D01*
G02X191780Y170195I-200J0D01*
G03X190944Y170499I-836J-997D01*
G03Y167895I0J-1302D01*
G03X191528Y168034I-1J1302D01*
G02X192108Y167676I180J-357D01*
G01Y167568D01*
G02X191528Y167210I-400J-1D01*
G03X190944Y167349I-585J-1163D01*
G03Y164745I0J-1302D01*
G03X191528Y164884I-1J1302D01*
G02X192108Y164526I180J-357D01*
G01Y164419D01*
G02X191528Y164061I-400J-1D01*
G03X190944Y164200I-585J-1163D01*
G03X189642Y162898I0J-1302D01*
G03X190001Y162000I1303J0D01*
G02X189995Y161441I-289J-276D01*
G01X189251Y160697D01*
G02X188692Y160691I-283J283D01*
G03X187794Y161050I-898J-944D01*
G03X186492Y159748I0J-1302D01*
G03X186851Y158850I1303J0D01*
G02X186845Y158291I-289J-276D01*
G01X186102Y157548D01*
G02X185543Y157542I-283J283D01*
G03X184645Y157901I-898J-944D01*
G03X183343Y156599I0J-1302D01*
G03X183702Y155701I1303J0D01*
G02X183696Y155142I-289J-276D01*
G01X182952Y154398D01*
G02X182393Y154392I-283J283D01*
G03X181495Y154751I-898J-944D01*
G03X180193Y153449I0J-1302D01*
G03X180552Y152551I1303J0D01*
G02X180546Y151992I-289J-276D01*
G01X174951Y146397D01*
X173608D01*
X173579Y146562D01*
G03X170621I-1479J-262D01*
G01X170592Y146397D01*
X154689D01*
X154645Y146419D01*
G03X153954Y146588I-692J-1333D01*
G03X153263Y146419I1J-1502D01*
G01X153219Y146397D01*
X150890D01*
X150846Y146419D01*
G03X150155Y146588I-692J-1333D01*
G03X149464Y146419I1J-1502D01*
G01X149420Y146397D01*
X147193D01*
X147066Y146524D01*
Y153687D01*
X147459Y154080D01*
X159060D01*
X159230Y154250D01*
X159351Y154202D01*
G03X159900Y154098I549J1397D01*
G03X161315Y155097I0J1502D01*
G01X161363Y155230D01*
X162500D01*
X166204Y158934D01*
X174180D01*
G03X175196Y158446I1016J814D01*
G03X176371Y159186I0J1303D01*
G01X176425Y159300D01*
X177117D01*
X177171Y159186D01*
G03X178346Y158446I1175J563D01*
G03X179648Y159748I0J1302D01*
G03X179584Y160150I-1302J-1D01*
G01X179547Y160267D01*
X180977Y161697D01*
X181094Y161659D01*
G03X181495Y161596I400J1239D01*
G03X182797Y162898I0J1302D01*
G03X181803Y164163I-1302J0D01*
G01X181650Y164200D01*
Y164745D01*
X181803Y164782D01*
G03X182797Y166047I-308J1265D01*
G03X182782Y166242I-1302J-2D01*
G01X182780Y166256D01*
Y166472D01*
X183086D01*
G03X183149Y166473I13J1166D01*
G02X183358Y166243I11J-200D01*
G03X183343Y166047I1287J-197D01*
G03X185947I1302J0D01*
G03X185136Y167253I-1302J0D01*
G02X185004Y167906I151J370D01*
G01X185060Y167962D01*
X185100Y167977D01*
G03X185947Y169197I-455J1220D01*
G03X185295Y170325I-1302J0D01*
G02X185212Y170955I199J347D01*
G01X185465Y171208D01*
Y171332D01*
X185529Y171391D01*
G03X185947Y172347I-884J956D01*
G03X185465Y173358I-1301J0D01*
G01Y174485D01*
G03Y176507I-819J1011D01*
G01Y177635D01*
G03Y179657I-819J1011D01*
G01Y180784D01*
G03Y182806I-819J1011D01*
G01Y183934D01*
G03X185947Y184945I-819J1011D01*
G01Y184967D01*
G02X186347Y185374I400J7D01*
G01X186740D01*
G03X187565Y185715I1J1166D01*
G01X187952Y186102D01*
X189420D01*
G02X189778Y185524I0J-400D01*
G03X189642Y184945I1166J-579D01*
G03X190944Y183643I1302J0D01*
G03X192242Y184841I0J1302D01*
G02X192923Y185092I399J-32D01*
G37*
G36*
G01X164858Y206858D02*
X166842D01*
X171127Y202573D01*
X172706D01*
X174030Y201250D01*
Y201233D01*
G03X173894Y200655I1166J-579D01*
G03X176498I1302J0D01*
G03X176381Y201195I-1302J1D01*
G01X176362Y201235D01*
Y201733D01*
G03X176316Y202061I-1167J4D01*
G02X176699Y202573I384J112D01*
G01X176873D01*
X177164Y202864D01*
G02X177444Y202866I141J-142D01*
G03X178346Y202503I902J939D01*
G03X179648Y203805I0J1302D01*
G03X179285Y204707I-1302J0D01*
G02X179287Y204987I144J139D01*
G01X180313Y206013D01*
G02X180593Y206016I142J-141D01*
G03X181495Y205653I902J939D01*
G03X182620Y206300I0J1302D01*
G01X183520D01*
G03X185770I1125J655D01*
G01X187700D01*
X188600Y205400D01*
X190934D01*
X192334Y204000D01*
Y202039D01*
G02X191701Y201714I-400J0D01*
G03X190944Y201957I-757J-1058D01*
G03X189642Y200655I0J-1302D01*
G03X190136Y199634I1302J0D01*
G02X190171Y199037I-248J-314D01*
G01X189234Y198100D01*
X188953D01*
G03X187794Y198808I-1159J-595D01*
G03X187038Y198566I0J-1302D01*
G02X186469Y198676I-232J325D01*
G03X185815Y199330I-1824J-1170D01*
G02X185705Y199899I215J337D01*
G03X185947Y200655I-1060J756D01*
G03X183343I-1302J0D01*
G03X183585Y199899I1302J0D01*
G02X183475Y199330I-325J-232D01*
G03X182821Y198675I1171J-1823D01*
G02X182252Y198565I-337J216D01*
G03X181495Y198808I-757J-1058D01*
G03Y196204I0J-1302D01*
G03X181972Y196295I-1J1302D01*
G02X182170Y195952I74J-186D01*
G03X181966Y195766I1355J-1691D01*
G01X177208D01*
G03X175676Y195132I-1J-2166D01*
G01X174744Y194200D01*
X171823D01*
G03X170800Y194602I-1023J-1101D01*
G03X169831Y194247I1J-1502D01*
G01X169775Y194200D01*
X169364D01*
X166152Y197412D01*
G03X164620Y198046I-1531J-1532D01*
G01X164000D01*
Y206000D01*
X164858Y206858D01*
G37*
G36*
G01X176233Y218679D02*
X176458D01*
X177116Y218021D01*
G03X178111Y217454I1532J1532D01*
G01X178165Y217440D01*
X178864Y216741D01*
X179794D01*
G02X180194Y216356I0J-400D01*
G03X182796I1301J47D01*
G02X183196Y216741I400J-15D01*
G01X191859D01*
X193200Y215400D01*
Y212197D01*
Y209700D01*
X192865Y209365D01*
G02X192589Y209359I-141J142D01*
G03X191800Y209666I-789J-860D01*
G01X189881D01*
X189029Y210519D01*
X189014Y210559D01*
G03X187794Y211406I-1220J-455D01*
G03X186492Y210104I0J-1302D01*
G03X186609Y209565I1302J0D01*
G02X186244Y209000I-364J-165D01*
G01X186195D01*
G02X185830Y209565I-1J400D01*
G03X185947Y210104I-1185J539D01*
G03X183343I-1302J0D01*
G03X183460Y209565I1302J0D01*
G02X183095Y209000I-364J-165D01*
G01X181600D01*
X180110Y207510D01*
G02X179479Y207596I-283J283D01*
G03X178346Y208257I-1133J-641D01*
G03X177044Y206955I0J-1302D01*
G03X177073Y206683I1302J1D01*
G02X176681Y206200I-391J-83D01*
G01X176392D01*
Y206438D01*
X176406Y206474D01*
G03X176498Y206955I-1211J481D01*
G03X175196Y208257I-1302J0D01*
G03X174672Y208147I0J-1303D01*
G02X174114Y208468I-161J366D01*
G03X174110Y208496I-1489J-198D01*
G02X174669Y208914I397J52D01*
G03X175196Y208802I528J1190D01*
G03X173894Y210104I0J1302D01*
G03X173897Y210015I1302J-1D01*
G02X173314Y209633I-399J-27D01*
G03X172621Y209802I-692J-1333D01*
G03X171122Y208396I0J-1502D01*
G02X170440Y208139I-399J26D01*
G01X169730Y208849D01*
G03X168905Y209190I-824J-825D01*
G01X168252D01*
G02X167854Y209633I0J400D01*
G03X167863Y209794I-1493J164D01*
G03X167411Y210868I-1502J0D01*
G02X167382Y211408I280J286D01*
G03X167702Y212300I-1083J892D01*
G03X164898I-1402J0D01*
G03X165263Y211357I1401J0D01*
G02X165260Y210816I-296J-269D01*
G03X164859Y209794I1102J-1022D01*
G03X164868Y209633I1502J3D01*
G02X164470Y209190I-398J-43D01*
G01X164299D01*
G03X163543Y208913I-1J-1166D01*
G01X163487Y208865D01*
X163335D01*
X162842Y208372D01*
X161657D01*
X160801Y209228D01*
Y216138D01*
X161404Y216741D01*
X164281D01*
X166019Y218479D01*
X166131Y218450D01*
G03X166689Y218376I561J2093D01*
G01X168342D01*
G03X169446Y218679I-1J2167D01*
G01X172967D01*
G02X173351Y218166I0J-400D01*
G03X173298Y217800I1249J-368D01*
G03X175902I1302J0D01*
G03X175849Y218166I-1302J-2D01*
G02X176233Y218679I384J113D01*
G37*
G36*
G01X199864Y214615D02*
X207701D01*
X208614Y213702D01*
X208584Y213590D01*
G03X208540Y213254I1258J-336D01*
G03X209842Y211952I1302J0D01*
G03X210008Y211963I-3J1302D01*
G01X210021Y211964D01*
X210234D01*
Y211394D01*
X210021D01*
X210008Y211395D01*
G03X209842Y211406I-169J-1291D01*
G03Y208802I0J-1302D01*
G03X210008Y208813I-3J1302D01*
G01X210021Y208814D01*
X210234D01*
Y208245D01*
X210021D01*
X210008Y208246D01*
G03X209842Y208257I-169J-1291D01*
G03X208540Y206955I0J-1302D01*
G03X209836Y205653I1302J0D01*
G02X210234Y205253I-2J-400D01*
G01Y202357D01*
G02X209836Y201957I-400J0D01*
G03X208540Y200655I6J-1302D01*
G03X209842Y199353I1302J0D01*
G03X210008Y199364I-3J1302D01*
G01X210021Y199365D01*
X210234D01*
Y198796D01*
X210021D01*
X210008Y198797D01*
G03X209842Y198808I-169J-1291D01*
G03X208540Y197506I0J-1302D01*
G03X209836Y196204I1302J0D01*
G02X210234Y195804I-2J-400D01*
G01Y186647D01*
G02X209836Y186247I-400J0D01*
G03X208540Y184945I6J-1302D01*
G03X209842Y183643I1302J0D01*
G03X210008Y183654I-3J1302D01*
G01X210021Y183655D01*
X210234D01*
Y183085D01*
X210021D01*
X210008Y183086D01*
G03X209842Y183097I-169J-1291D01*
G03X208540Y181795I0J-1302D01*
G03X209836Y180493I1302J0D01*
G02X210234Y180093I-2J-400D01*
G01Y174476D01*
X201978D01*
G02X201606Y175022I0J400D01*
G03X201695Y175496I-1213J473D01*
G03X199091I-1302J0D01*
G03X199180Y175022I1302J-1D01*
G02X198808Y174476I-372J-146D01*
G01X198501D01*
G02X198334Y174785I1J200D01*
G03X198545Y175496I-1091J711D01*
G03X195941I-1302J0D01*
G03X196152Y174785I1302J0D01*
G02X195985Y174476I-168J-109D01*
G01X195737D01*
X194268Y175945D01*
Y189921D01*
G03X194566Y190700I-869J779D01*
G01Y193652D01*
X195827Y194912D01*
Y195020D01*
X196284Y195477D01*
G03X196571Y195950I-825J824D01*
G02X197021Y196223I381J-121D01*
G03X197243Y196204I222J1283D01*
G03Y198808I0J1302D01*
G03X197077Y198797I3J-1302D01*
G02X196626Y199194I-51J397D01*
G01Y199412D01*
X196854D01*
X196881Y199404D01*
G03X197243Y199353I361J1251D01*
G03Y201957I0J1302D01*
G03X197077Y201946I3J-1302D01*
G02X196626Y202343I-51J397D01*
G01Y202562D01*
X196854D01*
X196881Y202554D01*
G03X197243Y202503I361J1251D01*
G03Y205107I0J1302D01*
G03X197077Y205096I3J-1302D01*
G02X196626Y205493I-51J397D01*
G01Y211377D01*
X199864Y214615D01*
G37*
G36*
G01X212877Y274360D02*
X222094D01*
X223429Y273025D01*
Y263560D01*
G02X222988Y263162I-400J0D01*
G03X222833Y263170I-155J-1494D01*
G03Y260166I0J-1502D01*
G03X222988Y260174I0J1502D01*
G02X223429Y259776I41J-398D01*
G01Y256262D01*
X223296Y256215D01*
G03Y253385I504J-1415D01*
G01X223429Y253338D01*
Y248979D01*
X222675Y248225D01*
G03X222334Y247400I825J-824D01*
G01Y244657D01*
G02X221737Y244309I-400J0D01*
G03X221000Y244502I-737J-1309D01*
G03Y241498I0J-1502D01*
G03X222498Y242886I0J1502D01*
G01X222503Y242960D01*
X222697Y243153D01*
X223034Y242817D01*
Y235437D01*
X220703Y233106D01*
G02X220146Y233098I-283J283D01*
G03X219253Y233453I-893J-946D01*
G03X217951Y232151I0J-1302D01*
G03X217983Y231865I1302J1D01*
G02X217877Y231643I-195J-43D01*
G03X217575Y231425I523J-1043D01*
G01X215075Y228925D01*
G03X214734Y228100I825J-824D01*
G01Y227137D01*
X214442Y226845D01*
G02X213885Y226837I-283J283D01*
G03X212991Y227192I-894J-948D01*
G03X211689Y225890I0J-1302D01*
G03X211788Y225393I1302J1D01*
G03X211575Y225225I611J-994D01*
G01X211102Y224752D01*
X210846Y225008D01*
X210934Y225143D01*
G03X211144Y225852I-1092J709D01*
G03X209842Y227154I-1302J0D01*
G03X208622Y226307I0J-1302D01*
G01X208607Y226267D01*
X208551Y226211D01*
G02X207898Y226343I-283J283D01*
G03X206692Y227154I-1206J-491D01*
G03Y224550I0J-1302D01*
G03X206797Y224554I3J1302D01*
G02X207011Y224329I16J-199D01*
G03X207002Y224198I1157J-145D01*
G02X206787Y224002I-200J3D01*
G03X206692Y224005I-89J-1299D01*
G03X205522Y223273I0J-1301D01*
G01X205467Y223161D01*
X204767D01*
X204712Y223273D01*
G03X202372I-1170J-569D01*
G01X202317Y223161D01*
X201618D01*
X201563Y223273D01*
G03X199223I-1170J-569D01*
G01X199168Y223161D01*
X198468D01*
X198413Y223273D01*
G03X197243Y224005I-1170J-569D01*
G03X196785Y223922I-1J-1302D01*
G02X196551Y224225I-71J187D01*
G03X196685Y224471I-950J677D01*
G02X196920Y224591I186J-74D01*
G03X197243Y224550I324J1261D01*
G03Y227154I0J1302D01*
G03X197184Y227153I-7J-1302D01*
G02X196766Y227552I-18J400D01*
G01Y230218D01*
X198900D01*
G02X199251Y229627I0J-400D01*
G03X199091Y229002I1141J-625D01*
G03X201695I1302J0D01*
G03X201535Y229627I-1301J0D01*
G02X201886Y230218I351J191D01*
G01X202049D01*
G02X202400Y229627I0J-400D01*
G03X202240Y229002I1141J-625D01*
G03X204844I1302J0D01*
G03X204498Y229886I-1302J0D01*
G02X204645Y230222I147J136D01*
G01X204793D01*
X205778Y231207D01*
X205917Y231105D01*
G03X206692Y230849I775J1045D01*
G03X207994Y232151I0J1302D01*
G03X207738Y232926I-1301J0D01*
G01X207636Y233065D01*
X208936Y234365D01*
X209071Y234284D01*
G03X209746Y234095I676J1113D01*
G03X211048Y235397I0J1302D01*
G03X210859Y236072I-1302J-1D01*
G01X210778Y236207D01*
X215220Y240649D01*
Y242594D01*
X215382Y242625D01*
G03X216602Y244100I-282J1475D01*
G03X216154Y245170I-1502J0D01*
G02X216238Y245803I281J285D01*
G03X217002Y247111I-738J1308D01*
G03X215595Y248610I-1502J0D01*
G02X215220Y249009I25J399D01*
G01Y251411D01*
G02X215597Y251811I400J1D01*
G03X217012Y253310I-86J1499D01*
G03X216974Y253645I-1502J-1D01*
G02X217246Y254116I390J89D01*
G03X218302Y255550I-446J1434D01*
G03X216800Y257052I-1502J0D01*
G03X215868Y256728I0J-1502D01*
G02X215220Y257042I-248J314D01*
G01Y260560D01*
G03Y262404I-1187J922D01*
G01Y268434D01*
X217017D01*
X218397Y267053D01*
X218403Y266980D01*
G03X219900Y265598I1497J120D01*
G03X221402Y267100I0J1502D01*
G03X220228Y268566I-1502J0D01*
G01X220171Y268578D01*
X218325Y270425D01*
G03X217500Y270766I-824J-825D01*
G01X214283D01*
X212186Y272864D01*
Y273669D01*
X212877Y274360D01*
G37*
G36*
G01X201619Y270991D02*
X210759D01*
X212975Y268775D01*
G03X213046Y268710I823J827D01*
G01X213971Y267785D01*
Y262992D01*
X213802Y262966D01*
G03Y259998I232J-1484D01*
G01X213971Y259972D01*
Y245091D01*
G03Y243109I1130J-991D01*
G01Y241944D01*
X205063Y233036D01*
G02X204489Y233044I-283J283D01*
G03X203542Y233453I-947J-892D01*
G03X202240Y232151I0J-1302D01*
G03X202305Y231745I1302J0D01*
G02X201925Y231220I-380J-125D01*
G01X201505D01*
Y231472D01*
X201530Y231517D01*
G03X201695Y232151I-1137J634D01*
G03X199091I-1302J0D01*
G03X199156Y231745I1302J0D01*
G02X198776Y231220I-380J-125D01*
G01X196766D01*
Y233601D01*
G02X197184Y234000I400J-1D01*
G03X197243Y233999I52J1301D01*
G03Y236603I0J1302D01*
G03X197003Y236581I-2J-1302D01*
G01X196985Y236577D01*
X196766D01*
Y236800D01*
G03X196425Y237625I-1166J1D01*
G01X195635Y238415D01*
Y238730D01*
G02X196211Y239090I400J1D01*
G03X196827Y238947I617J1259D01*
G03Y241751I0J1402D01*
G03X196211Y241608I1J-1402D01*
G02X195635Y241968I-176J359D01*
G01Y242647D01*
X199337Y246349D01*
X199388Y246363D01*
G03X200438Y247413I-398J1448D01*
G01X200452Y247464D01*
X204124Y251136D01*
Y253686D01*
X204515Y254077D01*
G03X204622Y254200I-825J825D01*
G02X205206Y254259I319J-241D01*
G03X206200Y253883I994J1126D01*
G03X207702Y255385I0J1502D01*
G03X206823Y256752I-1502J0D01*
G02X206675Y257365I165J364D01*
G03X207002Y258300I-1175J936D01*
G03X205500Y259802I-1502J0D01*
G03X204670Y259552I0J-1503D01*
G03X204515Y259745I-982J-630D01*
G01X202735Y261525D01*
G03X202549Y261676I-824J-825D01*
G01X202365Y261860D01*
X202409Y261980D01*
G03X202502Y262500I-1409J520D01*
G03X202127Y263493I-1502J0D01*
G02X202148Y264044I300J264D01*
G03X202602Y265120I-1048J1076D01*
G03X201226Y266617I-1502J0D01*
G02X200860Y267015I34J398D01*
G01Y270232D01*
X201619Y270991D01*
G37*
G36*
G01X234217Y269097D02*
X235903D01*
X237865Y267135D01*
Y264427D01*
G03Y261735I666J-1346D01*
G01Y259089D01*
G02X237669Y258889I-200J0D01*
G03Y255885I31J-1502D01*
G02X237865Y255685I-4J-200D01*
G01Y249786D01*
G02X237673Y249586I-200J0D01*
G03Y246584I57J-1501D01*
G02X237865Y246384I-8J-200D01*
G01Y245023D01*
X236096Y242376D01*
G03X235969Y242140I1134J-762D01*
G01X235080Y239992D01*
X233642Y238554D01*
Y236520D01*
X232437Y233612D01*
G03X232410Y233540I1266J-516D01*
G02X232172Y233413I-188J67D01*
G03X231851Y233453I-320J-1262D01*
G03X230549Y232151I0J-1302D01*
G03X230634Y231690I1302J2D01*
G03X230278Y231433I611J-1222D01*
G01X229420Y230575D01*
G03X229163Y230219I965J-967D01*
G03X228702Y230304I-463J-1217D01*
G03X227400Y229002I0J-1302D01*
G03X227423Y228758I1302J0D01*
G03X227159Y228584I615J-1220D01*
G02X226834Y228773I-128J153D01*
G03X226854Y229002I-1282J227D01*
G03X225552Y227700I-1302J0D01*
G03X225862Y227737I2J1302D01*
G02X226084Y227445I48J-194D01*
G03X225999Y227266I1189J-674D01*
G02X225783Y227140I-187J72D01*
G03X225590Y227154I-190J-1288D01*
G03X224288Y225852I0J-1302D01*
G03X224290Y225778I1302J-2D01*
G01Y225566D01*
X223740D01*
Y225778D01*
G03X223742Y225852I-1300J72D01*
G03X221138I-1302J0D01*
G03X221803Y224717I1301J0D01*
G02X221890Y224085I-196J-349D01*
G01X221474Y223669D01*
G03X221074Y222703I966J-966D01*
G03X222440Y221336I1367J0D01*
G03X223406Y221737I-1J1367D01*
G01X223829Y222159D01*
G02X224459Y222075I283J-283D01*
G03X225134Y221500I1131J645D01*
G01X225264Y221452D01*
Y220831D01*
X225129Y220784D01*
G03Y218322I422J-1231D01*
G01X225264Y218275D01*
Y217380D01*
X224900Y217016D01*
Y209126D01*
X225264Y208762D01*
Y207373D01*
X226272Y206365D01*
Y199215D01*
G02X225797Y198822I-400J0D01*
G03X225552Y198845I-244J-1279D01*
G03Y196241I0J-1302D01*
G03X225797Y196264I1J1302D01*
G02X226272Y195871I75J-393D01*
G01Y192916D01*
G02X225797Y192523I-400J0D01*
G03X225552Y192546I-244J-1279D01*
G03Y189942I0J-1302D01*
G03X225797Y189965I1J1302D01*
G02X226272Y189572I75J-393D01*
G01Y189304D01*
X226036D01*
X226003Y189316D01*
G03X225552Y189397I-452J-1221D01*
G03Y186793I0J-1302D01*
G03X225797Y186816I1J1302D01*
G02X226272Y186423I75J-393D01*
G01Y186154D01*
X226036D01*
X226003Y186166D01*
G03X225552Y186247I-452J-1221D01*
G03Y183643I0J-1302D01*
G03X225797Y183666I1J1302D01*
G02X226272Y183273I75J-393D01*
G01Y180327D01*
X225860Y179915D01*
X225759Y179931D01*
G03X225552Y179948I-210J-1285D01*
G03X224250Y178646I0J-1302D01*
G03X225356Y177359I1302J0D01*
G01X225526Y177333D01*
Y170510D01*
X225356Y170484D01*
G03Y167910I196J-1287D01*
G01X225526Y167884D01*
Y167360D01*
X225356Y167334D01*
G03Y164760I196J-1287D01*
G01X225526Y164734D01*
Y164211D01*
X225356Y164185D01*
G03Y161611I196J-1287D01*
G01X225526Y161585D01*
Y161061D01*
X225356Y161035D01*
G03Y158461I196J-1287D01*
G01X225526Y158435D01*
Y157912D01*
X225356Y157886D01*
G03Y155312I196J-1287D01*
G01X225526Y155286D01*
Y154674D01*
X225370Y154639D01*
G03Y152099I288J-1270D01*
G01X225526Y152064D01*
Y150073D01*
X241026Y134573D01*
X269887D01*
G02X270184Y133905I0J-400D01*
G03X269798Y132900I1115J-1005D01*
G01Y132886D01*
G02X269432Y132483I-400J-4D01*
G03X268059Y130987I129J-1496D01*
G03X271063I1502J0D01*
G01Y131001D01*
G02X271429Y131404I400J4D01*
G03X272802Y132900I-129J1496D01*
G03X272416Y133905I-1501J0D01*
G02X272713Y134573I297J268D01*
G01X279640D01*
X280922Y133291D01*
Y133064D01*
G02X280328Y132714I-400J0D01*
G03X279600Y132902I-728J-1314D01*
G03Y129898I0J-1502D01*
G03X280328Y130086I0J1502D01*
G02X280922Y129736I194J-350D01*
G01Y127898D01*
G02X280496Y127499I-400J0D01*
G03X280400Y127502I-95J-1499D01*
G03Y124498I0J-1502D01*
G03X280496Y124501I1J1502D01*
G02X280922Y124102I26J-399D01*
G01Y123595D01*
X279563Y122236D01*
X272850D01*
G03X270354I-1248J-836D01*
G01X269731D01*
G03X268435Y122978I-1296J-761D01*
G03X268041Y122925I1J-1502D01*
G02X267536Y123311I-105J386D01*
G01Y124980D01*
G03X267224Y125734I-1067J0D01*
G01X266284Y126674D01*
G03X265530Y126986I-754J-755D01*
G01X263070D01*
G03X262316Y126674I0J-1067D01*
G01X261709Y126068D01*
X261448D01*
X261391Y126119D01*
G03X260388Y126503I-1003J-1118D01*
G03Y123499I0J-1502D01*
G03X261446Y123934I1J1502D01*
G01X262151D01*
G03X262905Y124247I-1J1067D01*
G01X263512Y124854D01*
X265088D01*
X265404Y124538D01*
Y122236D01*
X264436D01*
X261150Y118950D01*
X254921D01*
G02X254538Y119466I0J400D01*
G03X254602Y119900I-1438J434D01*
G03X251598I-1502J0D01*
G03X252473Y118535I1502J0D01*
G02X252589Y117889I-167J-363D01*
G01X250600Y115900D01*
X246900D01*
X244076Y118724D01*
X243686D01*
X243636Y118757D01*
G03X242812Y119003I-824J-1257D01*
G03X241940Y118724I0J-1502D01*
G01X240837D01*
G03X238963I-937J-1174D01*
G01X236176D01*
X236070Y118618D01*
G02X235516Y118606I-283J282D01*
G03X234500Y119002I-1016J-1105D01*
G03X232998Y117500I0J-1502D01*
G03X233515Y116366I1502J0D01*
G01X233520Y116362D01*
X233666Y116215D01*
X233341Y115890D01*
X231825D01*
G02X231503Y116527I0J400D01*
G03X231795Y117417I-1210J890D01*
G03X228791I-1502J0D01*
G03X229083Y116527I1502J0D01*
G02X228761Y115890I-322J-237D01*
G01X228500D01*
G02X228161Y116502I0J400D01*
G03X228389Y117297I-1274J796D01*
G03X225385I-1502J0D01*
G03X225613Y116502I1502J1D01*
G02X225274Y115890I-339J-212D01*
G01X224844D01*
G02X224520Y116523I1J400D01*
G03X224802Y117400I-1220J876D01*
G03X221798I-1502J0D01*
G03X222080Y116523I1502J-1D01*
G02X221756Y115890I-325J-233D01*
G01X218892D01*
X217988Y114986D01*
Y110120D01*
X217268Y109400D01*
X208162D01*
X207502Y110061D01*
Y119193D01*
X212222Y123914D01*
X213250D01*
G03X214004Y124226I0J1067D01*
G01X215924Y126146D01*
G03X216236Y126900I-755J754D01*
G01Y127498D01*
G02X216768Y127876I400J0D01*
G03X217262Y127792I495J1418D01*
G03X218764Y129294I0J1502D01*
G03X218185Y130479I-1502J0D01*
G02Y131109I246J315D01*
G03X218764Y132294I-923J1185D01*
G03X217262Y133796I-1502J0D01*
G03X216951Y133763I2J-1502D01*
G02X216468Y134155I-83J391D01*
G01Y170310D01*
X213440Y173338D01*
Y173655D01*
G02X213761Y173814I200J0D01*
G03X214547Y173550I786J1038D01*
G03Y176154I0J1302D01*
G03X214006Y176036I1J-1302D01*
G02X213440Y176400I-166J364D01*
G01Y180566D01*
X213554Y180621D01*
G03Y182969I-563J1174D01*
G01X213440Y183024D01*
Y183716D01*
X213554Y183771D01*
G03Y186119I-563J1174D01*
G01X213440Y186174D01*
Y196277D01*
X213554Y196332D01*
G03Y198680I-563J1174D01*
G01X213440Y198735D01*
Y199426D01*
X213554Y199481D01*
G03Y201829I-563J1174D01*
G01X213440Y201884D01*
Y202576D01*
X213554Y202631D01*
G03Y204979I-563J1174D01*
G01X213440Y205034D01*
Y205726D01*
X213554Y205781D01*
G03Y208129I-563J1174D01*
G01X213440Y208184D01*
Y208875D01*
X213554Y208930D01*
G03Y211278I-563J1174D01*
G01X213440Y211333D01*
Y212025D01*
X213554Y212080D01*
G03Y214428I-563J1174D01*
G01X213440Y214483D01*
Y218324D01*
X213554Y218379D01*
G03Y220727I-563J1174D01*
G01X213440Y220782D01*
Y221511D01*
X213554Y221566D01*
G03X214293Y222740I-563J1174D01*
G03X214235Y223126I-1302J2D01*
G02X214334Y223363I191J59D01*
G03X214625Y223575I-533J1038D01*
G01X214948Y223898D01*
X215213Y223633D01*
X215107Y223494D01*
G03X214839Y222703I1033J-791D01*
G03X216141Y224005I1302J0D01*
G03X216045Y224001I6J-1302D01*
G02X215733Y224683I-29J399D01*
G01X216725Y225675D01*
G03X217066Y226500I-825J824D01*
G01Y227595D01*
X217664Y228193D01*
G02X218254Y228167I283J-283D01*
G03X219253Y227700I999J835D01*
G03X220555Y229002I0J1302D01*
G03X220523Y229291I-1302J2D01*
G02X220642Y229520I195J44D01*
G03X220863Y229640I-443J1079D01*
G02X221166Y229413I113J-165D01*
G03X221100Y229002I1236J-409D01*
G03X223704I1302J0D01*
G03X222489Y230301I-1302J0D01*
G02X222233Y230983I27J399D01*
G01X225025Y233775D01*
G03X225366Y234600I-825J824D01*
G01Y235896D01*
X225920Y236450D01*
Y244644D01*
G03Y247356I-644J1356D01*
G01Y248170D01*
X226525Y248775D01*
G03X226866Y249600I-825J824D01*
G01Y254799D01*
G02X227277Y255199I400J0D01*
G03X227316Y255198I58J1501D01*
G03X228031Y255379I0J1503D01*
G02X228595Y255169I190J-352D01*
G03X230000Y254198I1405J531D01*
G03Y257202I0J1502D01*
G03X229285Y257021I0J-1503D01*
G02X228721Y257231I-190J352D01*
G03X227316Y258202I-1405J-531D01*
G03X226803Y258112I-1J-1502D01*
G02X226266Y258488I-137J376D01*
G01Y264200D01*
G03X226252Y264385I-1166J5D01*
G02X226596Y264845I395J63D01*
G03X227907Y266335I-191J1490D01*
G03X226794Y267786I-1502J0D01*
G02X226615Y268455I104J386D01*
G01X227195Y269035D01*
X227275Y269038D01*
G03X227627Y269090I-42J1501D01*
G01X227653Y269097D01*
X231329D01*
X231379Y268972D01*
G03X231987Y268252I1394J560D01*
G02X232041Y267611I-210J-340D01*
G03X231531Y266483I992J-1128D01*
G03X234535I1502J0D01*
G03X233819Y267763I-1502J0D01*
G02X233765Y268404I210J340D01*
G03X234167Y268972I-992J1128D01*
G01X234217Y269097D01*
G37*
G36*
G01X219307Y114888D02*
X230888D01*
X231355Y114422D01*
Y111991D01*
X231206Y111952D01*
G03Y109048I387J-1452D01*
G01X231355Y109009D01*
Y105567D01*
X231146Y105358D01*
X230574D01*
X230566Y105350D01*
X218833D01*
X217952Y106231D01*
Y108668D01*
X218990Y109705D01*
Y114571D01*
X219307Y114888D01*
G37*
G36*
G01X265262Y253644D02*
X272851D01*
X273415Y253080D01*
Y249968D01*
X266616Y243169D01*
X261566D01*
X257397Y239000D01*
X254800D01*
X252403Y236604D01*
X250749D01*
G03X250697Y236602I24J-1302D01*
G02X250516Y236902I-8J200D01*
G03X250702Y237600I-1217J698D01*
G03X247898I-1402J0D01*
G03X249163Y236205I1402J0D01*
G02X249505Y235688I-40J-398D01*
G03X249446Y235301I1244J-388D01*
G03X249750Y234465I1303J0D01*
G02X249726Y233926I-307J-256D01*
G01X248974Y233174D01*
G02X248435Y233150I-283J283D01*
G03X247599Y233454I-836J-999D01*
G01X244450D01*
G03Y230848I0J-1303D01*
G01X245683D01*
G02X245966Y230166I0J-400D01*
G01X245565Y229765D01*
X245423Y229908D01*
X245421Y229909D01*
G03X244487Y230304I-934J-907D01*
G03X243185Y229002I0J-1302D01*
G03X243580Y228068I1302J0D01*
G01X243581Y228066D01*
X243724Y227924D01*
X243498Y227698D01*
Y225102D01*
X238972Y220575D01*
X238837Y220659D01*
G03X238150Y220855I-687J-1106D01*
G03X236848Y219553I0J-1302D01*
G03X237044Y218866I1302J0D01*
G01X237128Y218731D01*
X229650Y211253D01*
Y209642D01*
X228937Y208929D01*
X226513D01*
X225901Y209541D01*
Y216601D01*
X226274Y216974D01*
X227773Y215475D01*
G03X228739Y215074I967J966D01*
G03X230106Y216441I0J1367D01*
G03X229705Y217407I-1367J-1D01*
G01X229299Y217813D01*
G02X229375Y218439I283J283D01*
G03X230004Y219553I-672J1114D01*
G03X229695Y220395I-1302J0D01*
G01X231047Y221747D01*
G03X231889Y221438I842J993D01*
G03X233191Y222740I0J1302D01*
G03X233030Y223367I-1301J0D01*
G03X233292Y223564I-563J1022D01*
G01X234315Y224587D01*
G03X234439Y224734I-827J823D01*
G03X235038Y224588I599J1156D01*
G03X236340Y225890I0J1302D01*
G03X236253Y226358I-1302J0D01*
G01X236206Y226479D01*
X237898Y228170D01*
G03X238224Y228808I-825J824D01*
G01X238231Y228851D01*
G03X238246Y229038I-1151J186D01*
G01Y232846D01*
X241694Y236294D01*
X242360D01*
G02X242750Y235805I0J-400D01*
G03X242718Y235518I1271J-287D01*
G03X245322I1302J0D01*
G03X244500Y236728I-1302J0D01*
G02X244265Y237217I148J372D01*
G03X244322Y237596I-1246J381D01*
G03X244046Y238397I-1303J-1D01*
G01X243937Y238537D01*
X246867Y241467D01*
X247913Y241900D01*
X253518D01*
X257480Y245862D01*
X258198Y246159D01*
X258262Y246143D01*
G03X258628Y246098I365J1457D01*
G03X260130Y247600I0J1502D01*
G03X260003Y248205I-1502J1D01*
G01X259948Y248330D01*
X265262Y253644D01*
G37*
G36*
G01X227114Y179635D02*
X229803D01*
X230052Y179386D01*
X230446Y178991D01*
Y177997D01*
X231842Y176601D01*
Y170511D01*
X231670Y170486D01*
G03Y167908I181J-1289D01*
G01X231842Y167883D01*
Y167361D01*
X231670Y167336D01*
G03Y164758I181J-1289D01*
G01X231842Y164733D01*
Y164212D01*
X231670Y164187D01*
G03X230549Y162898I181J-1289D01*
G03X231678Y161608I1301J0D01*
G01X231851Y161584D01*
Y161062D01*
X231678Y161038D01*
G03Y158458I172J-1290D01*
G01X231851Y158434D01*
Y157913D01*
X231678Y157889D01*
G03X230549Y156599I172J-1290D01*
G03X231784Y155299I1302J0D01*
G01X231860Y155295D01*
X233697Y153458D01*
X233701Y153382D01*
G03X235001Y152147I1300J67D01*
G03X235605Y152296I-1J1302D01*
G01X235735Y152364D01*
X245772Y142327D01*
X267102D01*
G02X267502Y141932I0J-400D01*
G03X270506I1502J18D01*
G02X270906Y142327I400J-5D01*
G01X276012D01*
X276624Y141715D01*
Y137570D01*
X275284Y136230D01*
X250962D01*
Y136798D01*
X249462D01*
Y136230D01*
X246956D01*
Y136798D01*
X245454D01*
Y136230D01*
X241393D01*
X227856Y149767D01*
G02X228047Y150439I283J283D01*
G03X229202Y151900I-347J1461D01*
G03X227700Y153402I-1502J0D01*
G03X227395Y153371I-1J-1502D01*
G02X226925Y153670I-81J391D01*
G03X226845Y153905I-1267J-300D01*
G01X226827Y153944D01*
Y156335D01*
X226831Y156353D01*
G03X226854Y156599I-1279J244D01*
G03X226831Y156845I-1302J2D01*
G01X226827Y156863D01*
Y159484D01*
X226831Y159502D01*
G03X226854Y159748I-1279J244D01*
G03X226831Y159994I-1302J2D01*
G01X226827Y160012D01*
Y162634D01*
X226831Y162652D01*
G03X226854Y162898I-1279J244D01*
G03X226830Y163148I-1302J1D01*
G01X226826Y163167D01*
Y165778D01*
X226830Y165797D01*
G03X226854Y166047I-1278J249D01*
G03X226830Y166297I-1302J1D01*
G01X226826Y166316D01*
Y168928D01*
X226830Y168947D01*
G03X226854Y169197I-1278J249D01*
G03X226830Y169447I-1302J1D01*
G01X226826Y169466D01*
Y178377D01*
X226830Y178396D01*
G03X226854Y178646I-1278J249D01*
G03X226830Y178896I-1302J1D01*
G01X226826Y178915D01*
Y179346D01*
X227114Y179635D01*
G37*
G36*
G01X238150Y167349D02*
G03Y164745I0J-1302D01*
G03X238249Y164749I-3J1302D01*
G02X238465Y164550I16J-199D01*
G01Y164395D01*
G02X238249Y164196I-200J0D01*
G03X238150Y164200I-102J-1298D01*
G03Y161596I0J-1302D01*
G03X238249Y161600I-3J1302D01*
G02X238465Y161401I16J-199D01*
G01Y161245D01*
G02X238249Y161046I-200J0D01*
G03X238150Y161050I-102J-1298D01*
G03Y158446I0J-1302D01*
G03X238249Y158450I-3J1302D01*
G02X238465Y158251I16J-199D01*
G01Y158096D01*
G02X238249Y157897I-200J0D01*
G03X238150Y157901I-102J-1298D01*
G03Y155297I0J-1302D01*
G03X239413Y156282I0J1302D01*
G02X240084Y156467I388J-97D01*
G01X244438Y152113D01*
X246374D01*
X249344Y149143D01*
X269108D01*
X274126Y154160D01*
X287239D01*
X287600Y153800D01*
Y147635D01*
X283932Y143967D01*
X270904D01*
G02X270505Y144384I0J400D01*
G03X270506Y144450I-1501J56D01*
G03X267502I-1502J0D01*
G03X267503Y144384I1502J-10D01*
G02X267104Y143967I-399J-17D01*
G01X248699D01*
X248690Y143976D01*
X246582D01*
X236182Y154376D01*
X235919D01*
X235862Y154426D01*
G03X235001Y154751I-861J-978D01*
G03X234482Y154643I0J-1301D01*
G01X234357Y154589D01*
X232991Y155955D01*
X233045Y156080D01*
G03X233153Y156599I-1193J519D01*
G03X232891Y157382I-1301J0D01*
G01Y158935D01*
G03X233171Y159748I-1040J813D01*
G03X233164Y159886I-1320J2D01*
G03X232891Y160572I-1223J-89D01*
G01Y162098D01*
G03X232993Y162273I-1115J767D01*
G03X233153Y162898I-1141J625D01*
G03X232891Y163681I-1301J0D01*
G01Y165264D01*
G03Y166830I-1039J783D01*
G01Y168414D01*
G03Y169980I-1039J783D01*
G01Y177863D01*
G03X233153Y178646I-1039J783D01*
G03X232314Y179863I-1302J0D01*
G01X232274Y179878D01*
X231738Y180414D01*
X231728D01*
X231492Y180650D01*
X227880D01*
X227298Y181232D01*
Y186959D01*
X227739Y187400D01*
X233386D01*
X234225Y186561D01*
G02X234191Y185965I-283J-283D01*
G03X233699Y184945I811J-1020D01*
G03X235001Y183643I1302J0D01*
G03X235873Y183978I0J1302D01*
G02X236415Y183971I267J-297D01*
G03X237149Y183590I1034J1095D01*
G01X237208Y183578D01*
X238465Y182321D01*
Y170896D01*
G02X238085Y170497I-400J1D01*
G03X236848Y169197I65J-1300D01*
G03X238150Y167895I1302J0D01*
G03X238249Y167899I-3J1302D01*
G02X238465Y167700I16J-199D01*
G01Y167544D01*
G02X238249Y167345I-200J0D01*
G03X238150Y167349I-102J-1298D01*
G37*
G36*
G01X275553Y253362D02*
X290005D01*
X291466Y251901D01*
Y237175D01*
X290638Y236347D01*
X290558Y236346D01*
G03X289599Y235976I29J-1502D01*
G02X289073I-263J302D01*
G03X288086Y236346I-987J-1131D01*
G03X286584Y234844I0J-1502D01*
G03X286645Y234421I1502J1D01*
G02X286261Y233909I-384J-112D01*
G01X284134D01*
G02X283786Y234508I-1J400D01*
G03X283985Y235254I-1303J747D01*
G03X282483Y236756I-1502J0D01*
G03X281496Y236386I0J-1501D01*
G02X280970I-263J302D01*
G03X279983Y236756I-987J-1131D01*
G03X278481Y235254I0J-1502D01*
G03X278680Y234508I1502J1D01*
G02X278332Y233909I-347J-199D01*
G01X271107D01*
X269766Y235250D01*
X267212D01*
X258648Y226686D01*
G02X258055Y226715I-283J282D01*
G03X257048Y227192I-1007J-824D01*
G03X255746Y225890I0J-1302D01*
G03X256223Y224883I1301J0D01*
G02X256252Y224290I-253J-310D01*
G01X255848Y223886D01*
X254443D01*
X254406Y223902D01*
G03X253898Y224005I-508J-1199D01*
G03X253390Y223902I0J-1302D01*
G01X253353Y223886D01*
X251816D01*
X251610Y223680D01*
G03X250749Y224005I-861J-978D01*
G03X249447Y222703I0J-1302D01*
G03X249772Y221842I1303J0D01*
G01X247029Y219099D01*
X246979Y219084D01*
G03X245735Y218354I783J-2759D01*
G01X245734D01*
X245374Y217993D01*
X245373D01*
G03X244855Y216978I1306J-1306D01*
G01X244845Y216915D01*
X242168Y214238D01*
X242031Y214331D01*
G03X241300Y214556I-732J-1077D01*
G03X239998Y213254I0J-1302D01*
G03X240018Y213027I1302J0D01*
G02X239861Y212796I-197J-35D01*
G03X238660Y211321I305J-1475D01*
G01Y210730D01*
X237668Y209738D01*
X236908D01*
G03X236746Y209730I-7J-1506D01*
G02X236303Y210122I-43J398D01*
G03X235001Y211406I-1302J-18D01*
G03X233699Y210104I0J-1302D01*
G03X233981Y209295I1301J0D01*
G02X233668Y208646I-313J-249D01*
G01X231176D01*
X230698Y209124D01*
Y210751D01*
X238197Y218250D01*
X238269Y218256D01*
G03X239447Y219434I-119J1297D01*
G01X239453Y219506D01*
X245074Y225126D01*
Y227840D01*
G03X245652Y228421I-587J1162D01*
G01X245667Y228451D01*
X248225Y231008D01*
X248248Y231021D01*
G03X248729Y231502I-649J1130D01*
G01X248742Y231525D01*
X248926Y231710D01*
G02X249571Y231597I283J-283D01*
G03X250749Y230849I1178J554D01*
G03X252051Y232151I0J1302D01*
G03X251061Y233415I-1302J0D01*
G01X251006Y233429D01*
X250826Y233609D01*
X251215Y233998D01*
X253898D01*
G03X255200Y235301I0J1302D01*
G03X254453Y236479I-1302J0D01*
G02X254340Y237124I170J362D01*
G01X255016Y237800D01*
X257747D01*
X262115Y242168D01*
X267031D01*
X267095Y242232D01*
X267631D01*
X274648Y249249D01*
Y252456D01*
X275553Y253362D01*
G37*
G36*
G01X284278Y291400D02*
X292200D01*
X293890Y289710D01*
Y274192D01*
X294248Y273834D01*
Y267000D01*
G03X294255Y266855I1751J12D01*
G01X294262Y266762D01*
X288200Y260700D01*
X280500D01*
X276100Y265100D01*
Y271700D01*
X269600Y278200D01*
Y288198D01*
X272800Y291398D01*
X284219D01*
G03X284274Y291400I-15J1166D01*
G01X284278D01*
G37*
G36*
G01X299931Y240007D02*
X341354D01*
Y191423D01*
G02X340711Y191105I-400J0D01*
G03X339800Y191413I-911J-1193D01*
G03Y188409I0J-1502D01*
G03X340711Y188717I0J1501D01*
G02X341354Y188399I243J-318D01*
G01Y187423D01*
G02X340711Y187105I-400J0D01*
G03X339800Y187413I-911J-1193D01*
G03Y184409I0J-1502D01*
G03X340711Y184717I0J1501D01*
G02X341354Y184399I243J-318D01*
G01Y181423D01*
G02X340711Y181105I-400J0D01*
G03X339800Y181413I-911J-1193D01*
G03X338298Y179911I0J-1502D01*
G03X338877Y178726I1502J0D01*
G02Y178096I-246J-315D01*
G03X338298Y176911I923J-1185D01*
G03X339800Y175409I1502J0D01*
G03X340711Y175717I0J1501D01*
G02X341354Y175399I243J-318D01*
G01Y171423D01*
G02X340711Y171105I-400J0D01*
G03X339800Y171413I-911J-1193D01*
G03Y168409I0J-1502D01*
G03X340711Y168717I0J1501D01*
G02X341354Y168399I243J-318D01*
G01Y167423D01*
G02X340711Y167105I-400J0D01*
G03X339800Y167413I-911J-1193D01*
G03Y164409I0J-1502D01*
G03X340711Y164717I0J1501D01*
G02X341354Y164399I243J-318D01*
G01Y161094D01*
X340728D01*
X340675Y161131D01*
G03X339800Y161413I-876J-1220D01*
G03X338875Y161094I0J-1501D01*
G01X332330D01*
G03X330480I-925J-1182D01*
G01X325282D01*
G02X324883Y161470I0J400D01*
G03X323384Y162880I-1499J-92D01*
G03X322025Y162018I0J-1502D01*
G02X321381Y161906I-361J171D01*
G01X320720Y162567D01*
Y193593D01*
X318919Y195394D01*
Y199323D01*
X319268Y199672D01*
X319368Y199656D01*
G03X319601Y199638I232J1484D01*
G03X321103Y201140I0J1502D01*
G03X321085Y201373I-1502J1D01*
G01X321069Y201473D01*
X322111Y202515D01*
Y209199D01*
G03Y211315I-1066J1058D01*
G01Y211900D01*
X322150Y211953D01*
G03X322439Y212839I-1214J886D01*
G03X322111Y213776I-1502J0D01*
G01Y214458D01*
G03X322433Y215387I-1179J929D01*
G03X320994Y216888I-1502J0D01*
G01X320916Y216891D01*
X318613Y219194D01*
X318607Y219267D01*
G03X318316Y220035I-1497J-128D01*
G01X318276Y220089D01*
Y220340D01*
G03X317935Y221165I-1166J1D01*
G01X316175Y222925D01*
G03X315350Y223266I-824J-825D01*
G01X305145D01*
X302104Y224527D01*
G02X302018Y225217I153J369D01*
G03X302622Y226421I-898J1204D01*
G03X301802Y227759I-1502J0D01*
G02Y228472I182J357D01*
G03X302622Y229810I-682J1338D01*
G03X299618I-1502J0D01*
G03X300438Y228472I1502J0D01*
G02Y227759I-182J-356D01*
G03X299661Y226778I682J-1338D01*
G01X299648Y226724D01*
X299467Y226543D01*
X299191Y226819D01*
Y239267D01*
X299931Y240007D01*
G37*
G36*
G01X306700Y336381D02*
X329659D01*
X330664Y335376D01*
Y316859D01*
G03X331006Y316034I1166J0D01*
G01X335191Y311849D01*
Y291430D01*
X337321Y289300D01*
Y285047D01*
G02X336824Y284659I-400J0D01*
G03X336461Y284704I-365J-1457D01*
G03Y281700I0J-1502D01*
G03X336824Y281745I-2J1502D01*
G02X337321Y281357I97J-388D01*
G01Y270516D01*
X335552Y268747D01*
X300752D01*
X297752Y271748D01*
Y277867D01*
G02X298296Y278240I400J0D01*
G03X298840Y278138I544J1400D01*
G03Y281142I0J1502D01*
G03X298296Y281040I0J-1502D01*
G02X297752Y281413I-144J373D01*
G01Y302275D01*
X302300Y306823D01*
X302382Y306824D01*
G03X303613Y307337I-7J1751D01*
G01X304238Y307962D01*
G03X304306Y308032I-1222J1255D01*
G02X304939Y307983I298J-266D01*
G03X306200Y307298I1261J818D01*
G03Y310302I0J1502D01*
G03X305179Y309902I0J-1503D01*
G02X304553Y310010I-272J293D01*
G03X303000Y310952I-1553J-809D01*
G03X301762Y310438I1J-1751D01*
G01X301650Y310327D01*
X301568Y310326D01*
G03X300337Y309813I7J-1751D01*
G01X295575Y305052D01*
G02X294892Y305335I-283J283D01*
G01Y313142D01*
X295625Y313875D01*
G03X295966Y314700I-825J824D01*
G01Y322876D01*
X297343Y324253D01*
X297389Y324267D01*
G03X298371Y325249I-451J1433D01*
G01X298385Y325295D01*
X303850Y330760D01*
Y333531D01*
X306700Y336381D01*
G37*
G36*
G01X295187Y461587D02*
X299678D01*
X300086Y461179D01*
Y448087D01*
X302598Y445575D01*
X329773D01*
X332404Y442944D01*
Y433340D01*
G03X332386Y432809I8235J-545D01*
G03X332404Y432278I8253J14D01*
G01Y429284D01*
X337355Y424333D01*
Y405966D01*
X336756Y405367D01*
X316433D01*
X314050Y407750D01*
Y430353D01*
X307981Y436422D01*
X296239D01*
X294749Y437912D01*
Y461149D01*
X295187Y461587D01*
G37*
G36*
G01X314385Y467812D02*
X315625D01*
X315966Y467471D01*
Y453751D01*
X315647Y453432D01*
X314431D01*
X313969Y453894D01*
Y467396D01*
X314385Y467812D01*
G37*
%LPC*%
G75*
G36*
G01X34677Y239385D02*
G03Y240015I-246J315D01*
G02X34098Y241200I923J1185D01*
G02X37102I1502J0D01*
G02X36523Y240015I-1502J0D01*
G03Y239385I246J-315D01*
G02X37102Y238200I-923J-1185D01*
G02X34098I-1502J0D01*
G02X34677Y239385I1502J0D01*
G37*
G36*
G01X38105Y302475D02*
G03Y303102I-249J314D01*
G02X37537Y304278I933J1176D01*
G02X40541I1502J0D01*
G02X39973Y303102I-1501J0D01*
G03Y302475I249J-313D01*
G02X40541Y301299I-933J-1176D01*
G02X37537I-1502J0D01*
G02X38105Y302475I1501J0D01*
G37*
G36*
G01X29956Y303264D02*
G02X29136Y304602I682J1338D01*
G02X32140I1502J0D01*
G02X31320Y303264I-1502J0D01*
G03Y302551I182J-357D01*
G02X32140Y301213I-682J-1338D01*
G02X29136I-1502J0D01*
G02X29956Y302551I1502J0D01*
G03Y303264I-182J356D01*
G37*
G36*
G01X21555Y303288D02*
G02X20735Y304626I682J1338D01*
G02X23739I1502J0D01*
G02X22919Y303288I-1502J0D01*
G03Y302575I182J-357D01*
G02X23739Y301237I-682J-1338D01*
G02X20735I-1502J0D01*
G02X21555Y302575I1502J0D01*
G03Y303288I-182J357D01*
G37*
G36*
G01X153237Y55780D02*
G02Y61386I0J2803D01*
G01X161111D01*
G02Y55780I0J-2803D01*
G01X153237D01*
G37*
G36*
G01X165048Y49874D02*
G02Y55480I0J2803D01*
G01X172922D01*
G02Y49874I0J-2803D01*
G01X165048D01*
G37*
G36*
G01X176859Y55780D02*
G02Y61386I0J2803D01*
G01X184733D01*
G02Y55780I0J-2803D01*
G01X176859D01*
G37*
G36*
G01X153612Y138537D02*
G03X153880Y139029I-116J382D01*
G02X153823Y139440I1445J410D01*
G02X156827I1502J0D01*
G02X155763Y138003I-1502J0D01*
G03X155495Y137511I116J-382D01*
G02X155552Y137100I-1445J-410D01*
G02X152548I-1502J0D01*
G02X153612Y138537I1502J0D01*
G37*
G36*
G01X174537Y152276D02*
G03X173991Y152238I-253J-310D01*
G02X172890Y151758I-1101J1023D01*
G02Y154762I0J1502D01*
G02X173969Y154305I0J-1502D01*
G03X174516Y154278I288J278D01*
G02X175359Y154588I843J-991D01*
G02Y151984I0J-1302D01*
G02X174537Y152276I0J1303D01*
G37*
G36*
G01X170775Y199216D02*
G03Y199739I-303J262D01*
G02X170434Y200655I1060J916D01*
G02X173238I1402J0D01*
G02X172897Y199739I-1401J0D01*
G03Y199216I303J-262D01*
G02X173238Y198300I-1060J-916D01*
G02X170434I-1402J0D01*
G02X170775Y199216I1401J0D01*
G37*
G36*
G01X220355Y130479D02*
G03Y131109I-246J315D01*
G02X219776Y132294I923J1185D01*
G02X222780I1502J0D01*
G02X222201Y131109I-1502J0D01*
G03Y130479I246J-315D01*
G02X222780Y129294I-923J-1185D01*
G02X219776I-1502J0D01*
G02X220355Y130479I1502J0D01*
G37*
G36*
G01X224361D02*
G03Y131109I-246J315D01*
G02X223782Y132294I923J1185D01*
G02X226786I1502J0D01*
G02X226207Y131109I-1502J0D01*
G03Y130479I246J-315D01*
G02X226786Y129294I-923J-1185D01*
G02X223782I-1502J0D01*
G02X224361Y130479I1502J0D01*
G37*
G36*
G01X241882Y131011D02*
G02X241298Y132200I918J1189D01*
G02X242800Y133702I1502J0D01*
G02X244299Y132291I0J-1502D01*
G03X244871Y131955I399J25D01*
G02X245520Y132102I648J-1355D01*
G02X247022Y130600I0J-1502D01*
G02X246529Y129487I-1503J0D01*
G03X246525Y128898I268J-296D01*
G02X247002Y127800I-1025J-1098D01*
G02X245500Y126298I-1502J0D01*
G02X244021Y127538I0J1502D01*
G03X243390Y127790I-394J-70D01*
G02X242500Y127498I-890J1210D01*
G02X240998Y129000I0J1502D01*
G02X241819Y130339I1502J0D01*
G03X241882Y131011I-182J356D01*
G37*
G36*
G01X228480Y131104D02*
G02X227894Y132294I915J1190D01*
G02X230898I1502J0D01*
G02X230270Y131072I-1503J0D01*
G03X230258Y130430I232J-325D01*
G02X230844Y129240I-915J-1190D01*
G02X227840I-1502J0D01*
G02X228468Y130462I1503J0D01*
G03X228480Y131104I-232J325D01*
G37*
G36*
G01X242236Y224947D02*
G02X241300Y224550I-936J905D01*
G02X239998Y225853I1J1303D01*
G01Y229002D01*
G02X242602I1302J0D01*
G01Y226201D01*
X242607Y226179D01*
G02X242640Y225890I-1269J-291D01*
G02X242236Y224947I-1303J0D01*
G37*
G36*
G01X246797Y139765D02*
G02X247192Y139374I4J-391D01*
G01Y138820D01*
X246956D01*
Y137776D01*
X245454D01*
Y138820D01*
X245218D01*
Y139374D01*
G02X245613Y139765I391J0D01*
G01X245614Y139764D01*
X246796D01*
X246797Y139765D01*
G37*
G36*
G01X250804D02*
G02X251198Y139374I3J-391D01*
G01Y138820D01*
X250962D01*
Y137776D01*
X249462D01*
Y138820D01*
X249226D01*
Y139374D01*
G02X249620Y139765I391J0D01*
G01X249621Y139764D01*
X250803D01*
X250804Y139765D01*
G37*
G36*
G01X282431Y150048D02*
G03X281801I-315J-246D01*
G02X280616Y149469I-1185J923D01*
G02Y152473I0J1502D01*
G02X281801Y151894I0J-1502D01*
G03X282431I315J246D01*
G02X283616Y152473I1185J-923D01*
G02Y149469I0J-1502D01*
G02X282431Y150048I0J1502D01*
G37*
G36*
G01X250749Y227700D02*
G02Y230304I0J1302D01*
G01X253898D01*
G02Y227700I0J-1302D01*
G01X250749D01*
G37*
G36*
G01X257047Y230848D02*
X253898D01*
G02Y233454I0J1303D01*
G01X257047D01*
G02X257699Y233279I0J-1302D01*
G02Y231023I-652J-1128D01*
G02X257047Y230848I-652J1127D01*
G37*
G36*
G01X285694Y250384D02*
G03X285100Y250378I-294J-271D01*
G02X283974Y249870I-1126J994D01*
G02Y252874I0J1502D01*
G02X285080Y252388I0J-1501D01*
G03X285674Y252394I294J271D01*
G02X286800Y252902I1126J-994D01*
G02Y249898I0J-1502D01*
G02X285694Y250384I0J1501D01*
G37*
G36*
G01X284726Y278646D02*
G03X284096I-315J-246D01*
G02X282911Y278067I-1185J923D01*
G02Y281071I0J1502D01*
G02X284096Y280492I0J-1502D01*
G03X284726I315J246D01*
G02X285911Y281071I1185J-923D01*
G02Y278067I0J-1502D01*
G02X284726Y278646I0J1502D01*
G37*
G36*
G01X330273Y190898D02*
G03Y191424I-302J263D01*
G02X329903Y192411I1131J987D01*
G02X332907I1502J0D01*
G02X332537Y191424I-1501J0D01*
G03Y190898I302J-263D01*
G02Y188924I-1131J-987D01*
G03Y188398I302J-263D01*
G02X332907Y187411I-1131J-987D01*
G02X329903I-1502J0D01*
G02X330273Y188398I1501J0D01*
G03Y188924I-302J263D01*
G02Y190898I1131J987D01*
G37*
G36*
G01X330489Y181736D02*
G02X329903Y182926I915J1190D01*
G02X332907I1502J0D01*
G02X332321Y181736I-1501J0D01*
G03Y181101I244J-317D01*
G02X332907Y179911I-915J-1190D01*
G02X332537Y178924I-1501J0D01*
G03Y178398I302J-263D01*
G02Y176424I-1131J-987D01*
G03Y175898I302J-263D01*
G02X332907Y174911I-1131J-987D01*
G02X329903I-1502J0D01*
G02X330273Y175898I1501J0D01*
G03Y176424I-302J263D01*
G02Y178398I1131J987D01*
G03Y178924I-302J263D01*
G02X329903Y179911I1131J987D01*
G02X330489Y181101I1501J0D01*
G03Y181736I-244J317D01*
G37*
G36*
G01X325641Y228400D02*
G02X324821Y229738I682J1338D01*
G02X327825I1502J0D01*
G02X327005Y228400I-1502J0D01*
G03Y227687I182J-357D01*
G02X327825Y226349I-682J-1338D01*
G02X324821I-1502J0D01*
G02X325641Y227687I1502J0D01*
G03Y228400I-182J357D01*
G37*
G36*
G01X334041D02*
G02X333221Y229738I682J1338D01*
G02X336225I1502J0D01*
G02X335405Y228400I-1502J0D01*
G03Y227687I182J-357D01*
G02X336225Y226349I-682J-1338D01*
G02X333221I-1502J0D01*
G02X334041Y227687I1502J0D01*
G03Y228400I-182J357D01*
G37*
G36*
G01X317240Y228424D02*
G02X316420Y229762I682J1338D01*
G02X319424I1502J0D01*
G02X318604Y228424I-1502J0D01*
G03Y227711I182J-357D01*
G02X319424Y226373I-682J-1338D01*
G02X316420I-1502J0D01*
G02X317240Y227711I1502J0D01*
G03Y228424I-182J357D01*
G37*
G36*
G01X308839Y228448D02*
G02X308019Y229786I682J1338D01*
G02X311023I1502J0D01*
G02X310203Y228448I-1502J0D01*
G03Y227735I182J-357D01*
G02X311023Y226397I-682J-1338D01*
G02X308019I-1502J0D01*
G02X308839Y227735I1502J0D01*
G03Y228448I-182J357D01*
G37*
G36*
G01X301863Y280792D02*
G03Y281381I-271J294D01*
G02X301377Y282487I1015J1106D01*
G02X304381I1502J0D01*
G02X303895Y281381I-1501J0D01*
G03Y280792I271J-295D01*
G02X304381Y279686I-1015J-1106D01*
G02X301377I-1502J0D01*
G02X301863Y280792I1501J0D01*
G37*
G36*
G01X323911Y327035D02*
G03Y327581I-292J273D01*
G02X323505Y328608I1096J1027D01*
G02X325007Y330110I1502J0D01*
G02X326061Y329678I0J-1502D01*
G03X326628Y329683I281J285D01*
G02X327704Y330137I1076J-1048D01*
G02X329206Y328635I0J-1502D01*
G02X328800Y327608I-1502J0D01*
G03Y327062I292J-273D01*
G02X329206Y326035I-1096J-1027D01*
G02X328836Y325048I-1501J0D01*
G03Y324522I302J-263D01*
G02X329206Y323535I-1131J-987D01*
G02X327704Y322033I-1502J0D01*
G02X326650Y322465I0J1502D01*
G03X326083Y322460I-281J-285D01*
G02X325007Y322006I-1076J1048D01*
G02X323505Y323508I0J1502D01*
G02X323875Y324495I1501J0D01*
G03Y325021I-302J263D01*
G02X323505Y326008I1131J987D01*
G02X323911Y327035I1502J0D01*
G37*
G36*
G01X311060Y283787D02*
G02X310168Y285160I611J1373D01*
G02X313172I1502J0D01*
G02X312755Y284122I-1502J1D01*
G03X312882Y283480I289J-276D01*
G02X313774Y282107I-611J-1373D01*
G02X310770I-1502J0D01*
G02X311187Y283145I1502J-1D01*
G03X311060Y283787I-289J276D01*
G37*
G54D22*
X39408Y195990D03*
X19100Y187420D03*
X24705Y258767D03*
X37485Y258807D03*
X41100Y248900D03*
X67700Y229725D03*
X112200Y234520D03*
X92500Y116200D03*
X86700Y119100D03*
X142300Y216300D03*
X146000Y216350D03*
X165500Y236100D03*
X176000Y140500D03*
X161900Y150500D03*
X165690Y149622D03*
X171700Y156900D03*
X170400Y214700D03*
X220866Y272160D03*
X217500Y264000D03*
X211265Y267300D03*
X206051Y247911D03*
X205900Y266130D03*
X274500Y131629D03*
X232300Y261200D03*
X230535Y244564D03*
X229630Y264404D03*
X211370Y117000D03*
X260200Y132395D03*
X233511Y129594D03*
X252374Y132159D03*
X234900Y126100D03*
X225300Y125200D03*
X221500Y125100D03*
X231100Y125600D03*
X215294Y117094D03*
X242195Y141003D03*
X232384Y148884D03*
X258500Y146400D03*
X286000Y242100D03*
X287755Y287538D03*
X285911Y269899D03*
X281889D03*
Y287636D03*
X323384Y169378D03*
X331405Y164911D03*
Y169911D03*
X323384Y173378D03*
Y177378D03*
X326932Y205685D03*
X326733Y209885D03*
X326731Y213648D03*
X337004Y202113D03*
Y206113D03*
Y210113D03*
X326733Y201485D03*
X337083Y197000D03*
X323384Y165378D03*
X309700Y294789D03*
X302800Y286200D03*
X327162Y278972D03*
X306500Y301500D03*
G54D23*
X181495Y229002D03*
X178346D03*
X174079Y234604D03*
X184645Y232151D03*
X187794Y229002D03*
X184645D03*
X197243Y156599D03*
Y166047D03*
Y159748D03*
X194094D03*
X197243Y162898D03*
X187794Y153449D03*
X178346Y156599D03*
X175196D03*
X181495D03*
Y159748D03*
X187794Y166047D03*
Y162898D03*
Y181795D03*
X190944Y172347D03*
Y175496D03*
X184645Y162898D03*
Y159748D03*
X187794Y169197D03*
Y175496D03*
Y172347D03*
Y178646D03*
X184645Y203805D03*
X178346Y200655D03*
Y197506D03*
X175196D03*
X187794Y200655D03*
X181495Y203805D03*
Y200655D03*
X187794Y213254D03*
X178346D03*
Y210104D03*
X175196Y213254D03*
X184645D03*
X190944D03*
X203542Y191244D03*
X206692D03*
Y178646D03*
Y181795D03*
X200393Y191244D03*
X197243D03*
Y178646D03*
X203542Y210104D03*
Y206955D03*
X206692D03*
X200393Y210104D03*
Y206955D03*
X203542Y200655D03*
Y197506D03*
X197243Y184945D03*
X209842Y232151D03*
X206692Y229002D03*
X203542Y225852D03*
X212991Y232151D03*
X200393Y225852D03*
X212991Y229002D03*
X209842D03*
X203542Y235301D03*
X219253Y156599D03*
X219290Y191207D03*
X219253Y188095D03*
X222402Y191244D03*
Y156599D03*
X219253Y166047D03*
Y169197D03*
X222402Y166047D03*
X219253Y159748D03*
X222402D03*
X219253Y162898D03*
X217697Y174852D03*
X219253Y178646D03*
X222402D03*
X219253Y203805D03*
Y213254D03*
Y210104D03*
Y206955D03*
X222402Y219553D03*
X219290Y225852D03*
Y222703D03*
X219253Y219553D03*
X222402Y213254D03*
Y206955D03*
X216103Y219591D03*
X222402Y197506D03*
X219253D03*
Y200655D03*
X222402Y162898D03*
Y169197D03*
X241300Y232151D03*
X235001Y219553D03*
X238150Y222703D03*
X238188Y225852D03*
X235038Y222740D03*
X228739Y213254D03*
X231889Y219591D03*
X228702Y162898D03*
Y159748D03*
Y166047D03*
Y169197D03*
X235001Y156599D03*
Y169197D03*
Y178646D03*
Y175496D03*
Y159748D03*
Y162898D03*
Y166047D03*
X250749Y225852D03*
X257048Y235301D03*
X247637Y225852D03*
G54D24*
X182764Y52677D03*
X168985Y58583D03*
G54D25*
X192400Y152804D03*
X220100Y237200D03*
%LPD*%
G75*
G54D10*
X-61000Y382816D03*
X-51000D03*
G54D20*
G01X102190Y63225D02*
X101311Y64104D01*
X100958D01*
X95878Y62000D01*
X59000D01*
X37300Y83700D01*
Y94301D01*
X28801Y102800D01*
X22957D01*
X5223Y120534D01*
Y309028D01*
X16049Y319854D01*
Y334205D01*
X15491Y335551D01*
X15490D01*
X14884Y337017D01*
X6980Y344921D01*
Y424154D01*
X9686Y430685D01*
X20701Y441700D01*
X48201D01*
X51521Y445020D01*
X60821D01*
X78445Y452320D01*
X82439D01*
X84400Y450359D01*
Y449175D01*
X85490Y448085D01*
G01X102190Y66725D02*
X100889Y65424D01*
X100695D01*
X95615Y63320D01*
X87566D01*
X86716Y64170D01*
X85366D01*
X84516Y63320D01*
X83166D01*
X82316Y64170D01*
X80966D01*
X80116Y63320D01*
X78766D01*
X77916Y64170D01*
X76566D01*
X75716Y63320D01*
X73664D01*
X72814Y64170D01*
X71464D01*
X70614Y63320D01*
X59547D01*
X38620Y84247D01*
Y94848D01*
X29348Y104120D01*
X23504D01*
X6543Y121081D01*
Y308481D01*
X17369Y319307D01*
Y334468D01*
X16004Y337765D01*
X15817Y337952D01*
Y337951D01*
X8300Y345468D01*
Y423891D01*
X10805Y429937D01*
X21248Y440380D01*
X29650D01*
X30450Y439580D01*
X31750D01*
X32550Y440380D01*
X42350D01*
X43150Y439580D01*
X44450D01*
X45250Y440380D01*
X48748D01*
X52068Y443700D01*
X61084D01*
X66502Y445943D01*
X67547Y445510D01*
X68749Y446008D01*
X69182Y447054D01*
Y447053D01*
X70383Y447550D01*
Y447551D01*
X71428Y447118D01*
X72630Y447615D01*
X73063Y448662D01*
Y448661D01*
X74827Y449392D01*
X75873Y448959D01*
X77075Y449457D01*
X77507Y450503D01*
Y450502D01*
X78708Y451000D01*
X81892D01*
X83080Y449812D01*
Y449175D01*
X81990Y448085D01*
G01X375964Y-215959D02*
X377004Y-216999D01*
Y-228056D01*
X377262Y-229514D01*
X376532Y-230556D01*
X368158Y-232033D01*
X366801Y-233969D01*
X367802Y-239640D01*
X369741Y-240996D01*
X379433Y-239288D01*
X380474Y-240018D01*
X381285Y-244608D01*
X380555Y-245650D01*
X368478Y-247780D01*
X367121Y-249718D01*
X368122Y-255388D01*
X370059Y-256744D01*
X379393Y-255099D01*
X380434Y-255829D01*
X381245Y-260419D01*
X380515Y-261461D01*
X368832Y-263522D01*
X367475Y-265459D01*
X368476Y-271129D01*
X370414Y-272485D01*
X379399Y-270901D01*
X380440Y-271631D01*
X381251Y-276221D01*
X380521Y-277263D01*
X368966Y-279302D01*
X367609Y-281239D01*
X368610Y-286909D01*
X370548Y-288265D01*
X379317Y-286719D01*
X380358Y-287449D01*
X381169Y-292039D01*
X380439Y-293081D01*
X369069Y-295087D01*
X367712Y-297024D01*
X368713Y-302694D01*
X370651Y-304050D01*
X379343Y-302518D01*
X380384Y-303249D01*
X381195Y-307839D01*
X380465Y-308881D01*
X369073Y-310890D01*
X367716Y-312827D01*
X368717Y-318497D01*
X370655Y-319853D01*
X379475Y-318298D01*
X380516Y-319028D01*
X381327Y-323618D01*
X380597Y-324660D01*
X369081Y-326692D01*
X367724Y-328629D01*
X368725Y-334299D01*
X370663Y-335655D01*
X379389Y-334117D01*
X380429Y-334847D01*
X381240Y-339437D01*
X380510Y-340479D01*
X369009Y-342507D01*
X367652Y-344445D01*
X368655Y-350115D01*
X370588Y-351474D01*
X379423Y-349916D01*
X380464Y-350645D01*
X381275Y-355235D01*
X380545Y-356278D01*
X369092Y-358298D01*
X367735Y-360235D01*
X368736Y-365904D01*
X370674Y-367260D01*
X379216Y-365755D01*
X380258Y-366486D01*
X380662Y-368779D01*
X380663D01*
X381069Y-371075D01*
X380339Y-372116D01*
X369117Y-374096D01*
X367762Y-376038D01*
X368764Y-381704D01*
X370700Y-383059D01*
X379286Y-381546D01*
X380328Y-382278D01*
X381138Y-386867D01*
X380408Y-387908D01*
X369001Y-389920D01*
X367646Y-391862D01*
X368646Y-397526D01*
X370583Y-398884D01*
X379437Y-397323D01*
X380479Y-398054D01*
X381291Y-402643D01*
X380561Y-403683D01*
X368957Y-405732D01*
X367600Y-407669D01*
X368603Y-413339D01*
X370540Y-414696D01*
X379521Y-413111D01*
X380563Y-413842D01*
X381373Y-418431D01*
X380643Y-419473D01*
X378831Y-419793D01*
X376944Y-421680D01*
Y-437105D01*
X375904Y-438145D01*
G01X379364Y-215959D02*
X378324Y-216999D01*
Y-227940D01*
X378658Y-229823D01*
X377300Y-231761D01*
X368926Y-233239D01*
X368197Y-234279D01*
X369008Y-238871D01*
X370050Y-239601D01*
X379743Y-237893D01*
X381680Y-239250D01*
X382585Y-244379D01*
X382586D01*
X382681Y-244917D01*
X381323Y-246855D01*
X369246Y-248985D01*
X368517Y-250027D01*
X369327Y-254620D01*
X370368Y-255349D01*
X379703Y-253704D01*
X381640Y-255061D01*
X382545Y-260190D01*
X382546D01*
X382641Y-260728D01*
X381283Y-262666D01*
X369600Y-264727D01*
X368871Y-265769D01*
X369681Y-270361D01*
X370723Y-271090D01*
X379709Y-269505D01*
X381646Y-270863D01*
X382647Y-276530D01*
X381289Y-278468D01*
X369734Y-280507D01*
X369005Y-281549D01*
X369815Y-286141D01*
X370857Y-286870D01*
X379627Y-285323D01*
X381564Y-286681D01*
X382565Y-292348D01*
X381207Y-294286D01*
X369837Y-296292D01*
X369108Y-297334D01*
X369918Y-301926D01*
X370960Y-302655D01*
X379654Y-301122D01*
X381590Y-302482D01*
X382591Y-308148D01*
X381233Y-310087D01*
X369841Y-312096D01*
X369112Y-313137D01*
X369922Y-317729D01*
X370964Y-318458D01*
X379785Y-316902D01*
X381722Y-318260D01*
X382723Y-323927D01*
X381365Y-325865D01*
X369849Y-327897D01*
X369120Y-328939D01*
X369930Y-333531D01*
X370972Y-334260D01*
X379699Y-332721D01*
X381635Y-334080D01*
X382636Y-339746D01*
X381278Y-341685D01*
X369777Y-343712D01*
X369048Y-344754D01*
X369861Y-349348D01*
X370899Y-350078D01*
X379732Y-348520D01*
X381669Y-349877D01*
X382671Y-355544D01*
X381313Y-357483D01*
X369860Y-359503D01*
X369131Y-360544D01*
X369941Y-365136D01*
X370983Y-365865D01*
X379526Y-364359D01*
X381463Y-365719D01*
X382465Y-371384D01*
X381107Y-373322D01*
X369886Y-375301D01*
X369157Y-376346D01*
X369969Y-380936D01*
X371009Y-381664D01*
X379597Y-380150D01*
X381534Y-381511D01*
X382534Y-387176D01*
X381176Y-389114D01*
X369770Y-391125D01*
X369041Y-392170D01*
X369852Y-396758D01*
X370893Y-397488D01*
X379747Y-395927D01*
X381685Y-397286D01*
X382687Y-402952D01*
X381329Y-404889D01*
X369725Y-406937D01*
X368996Y-407978D01*
X369808Y-412571D01*
X370849Y-413300D01*
X379831Y-411715D01*
X381769Y-413074D01*
X382769Y-418741D01*
X381411Y-420679D01*
X379470Y-421021D01*
X378264Y-422227D01*
Y-437105D01*
X379304Y-438145D01*
G01X396992Y-464207D02*
X398032Y-463167D01*
Y-444478D01*
X400391Y-442119D01*
X410931Y-440257D01*
X411659Y-439219D01*
X410848Y-434628D01*
X409805Y-433898D01*
X391836Y-437066D01*
X389899Y-435708D01*
X388898Y-430038D01*
X390258Y-428102D01*
X410616Y-424512D01*
X411346Y-423470D01*
X410536Y-418878D01*
X409490Y-418148D01*
X392355Y-421170D01*
X390418Y-419812D01*
X389417Y-414143D01*
X390775Y-412206D01*
X411044Y-408631D01*
X411772Y-407592D01*
X410962Y-402999D01*
X409916Y-402270D01*
X392534Y-405335D01*
X390597Y-403977D01*
X389634Y-398522D01*
X391167Y-396334D01*
X411026Y-392830D01*
X411754Y-391791D01*
X410944Y-387199D01*
X409899Y-386468D01*
X392079Y-389611D01*
X390142Y-388253D01*
X389141Y-382584D01*
X390501Y-380647D01*
X410871Y-377055D01*
X411601Y-376013D01*
X410791Y-371421D01*
X409745Y-370691D01*
X392598Y-373715D01*
X390661Y-372357D01*
X389607Y-366387D01*
X390717Y-364804D01*
X408881Y-361600D01*
X409609Y-360562D01*
X408799Y-355969D01*
X407752Y-355239D01*
X392777Y-357880D01*
X390840Y-356522D01*
X389839Y-350853D01*
X391197Y-348916D01*
X409095Y-345758D01*
X409823Y-344720D01*
X409013Y-340128D01*
X407968Y-339397D01*
X392322Y-342156D01*
X390385Y-340798D01*
X389384Y-335129D01*
X390744Y-333192D01*
X407503Y-330236D01*
X408233Y-329194D01*
X407422Y-324601D01*
X406382Y-323872D01*
X392706Y-326285D01*
X390769Y-324927D01*
X389767Y-319258D01*
X391126Y-317321D01*
X407152Y-314495D01*
X407882Y-313454D01*
X407072Y-308861D01*
X406029Y-308131D01*
X392728Y-310476D01*
X390789Y-309119D01*
X389788Y-303450D01*
X391146Y-301513D01*
X406755Y-298762D01*
X407484Y-297719D01*
X407483D01*
X406673Y-293126D01*
X405632Y-292397D01*
X392742Y-294671D01*
X390805Y-293313D01*
X389803Y-287644D01*
X391163Y-285707D01*
X407049Y-282905D01*
X407778Y-281865D01*
X406968Y-277272D01*
X405925Y-276542D01*
X392527Y-278904D01*
X390588Y-277547D01*
X389587Y-271878D01*
X390946Y-269942D01*
X407116Y-267090D01*
X407846Y-266049D01*
X407036Y-261456D01*
X405993Y-260727D01*
X392535Y-263099D01*
X390596Y-261742D01*
X389595Y-256073D01*
X390953Y-254136D01*
X406962Y-251313D01*
X407690Y-250273D01*
X406880Y-245680D01*
X405837Y-244950D01*
X392806Y-247249D01*
X390869Y-245891D01*
X389866Y-240210D01*
X391215Y-238286D01*
X407373Y-235437D01*
X408103Y-234395D01*
X407293Y-229802D01*
X406251Y-229073D01*
X392551Y-231490D01*
X390614Y-230132D01*
X389612Y-224465D01*
X390974Y-222526D01*
X407312Y-219644D01*
X408040Y-218604D01*
X407229Y-214012D01*
X406188Y-213282D01*
X392703Y-215659D01*
X390766Y-214302D01*
X389765Y-208634D01*
X391123Y-206696D01*
X407461Y-203814D01*
X408190Y-202774D01*
X407380Y-198181D01*
X406337Y-197452D01*
X392750Y-199848D01*
X390814Y-198490D01*
X389813Y-192822D01*
X391171Y-190884D01*
X407258Y-188047D01*
X407988Y-187005D01*
X407178Y-182412D01*
X406137Y-181683D01*
X392798Y-184036D01*
X390862Y-182677D01*
X389861Y-177010D01*
X391219Y-175072D01*
X407241Y-172246D01*
X407970Y-171205D01*
X407160Y-166612D01*
X406119Y-165883D01*
X392611Y-168265D01*
X390674Y-166907D01*
X389673Y-161239D01*
X391031Y-159301D01*
X406855Y-156510D01*
X407584Y-155469D01*
X406774Y-150876D01*
X405732Y-150147D01*
X392904Y-152410D01*
X390968Y-151051D01*
X389967Y-145384D01*
X391325Y-143448D01*
X394981Y-142800D01*
X397121Y-140661D01*
X398070Y-135277D01*
Y-122011D01*
X397080Y-121021D01*
G01X400392Y-464207D02*
X399352Y-463167D01*
Y-445025D01*
X401030Y-443347D01*
X411699Y-441463D01*
X413055Y-439529D01*
X412053Y-433860D01*
X410114Y-432503D01*
X392146Y-435670D01*
X391105Y-434940D01*
X390294Y-430349D01*
X391025Y-429308D01*
X411384Y-425718D01*
X412742Y-423780D01*
X411741Y-418109D01*
X409798Y-416753D01*
X392665Y-419774D01*
X391624Y-419044D01*
X390813Y-414453D01*
X391543Y-413412D01*
X411812Y-409837D01*
X413168Y-407902D01*
X412167Y-402230D01*
X410224Y-400875D01*
X392844Y-403939D01*
X391803Y-403209D01*
X391030Y-398831D01*
X391935Y-397539D01*
X411794Y-394036D01*
X413150Y-392101D01*
X412149Y-386431D01*
X410208Y-385073D01*
X392389Y-388215D01*
X391348Y-387485D01*
X390537Y-382894D01*
X391268Y-381853D01*
X411639Y-378261D01*
X412997Y-376323D01*
X411996Y-370652D01*
X410053Y-369296D01*
X392908Y-372319D01*
X391867Y-371589D01*
X391003Y-366697D01*
X391485Y-366010D01*
X409649Y-362806D01*
X411005Y-360872D01*
X410004Y-355200D01*
X408060Y-353844D01*
X393087Y-356484D01*
X392046Y-355754D01*
X391235Y-351163D01*
X391965Y-350122D01*
X409863Y-346964D01*
X411219Y-345030D01*
X410218Y-339360D01*
X408277Y-338002D01*
X392632Y-340760D01*
X391591Y-340030D01*
X390780Y-335439D01*
X391511Y-334398D01*
X408271Y-331442D01*
X409629Y-329504D01*
X408628Y-323833D01*
X406692Y-322476D01*
X393016Y-324889D01*
X391975Y-324159D01*
X391163Y-319568D01*
X391894Y-318527D01*
X407920Y-315701D01*
X409278Y-313764D01*
X408277Y-308093D01*
X406338Y-306736D01*
X393037Y-309081D01*
X391994Y-308351D01*
X391184Y-303760D01*
X391914Y-302719D01*
X407524Y-299968D01*
X408879Y-298028D01*
X407879Y-292358D01*
X405941Y-291002D01*
X393052Y-293275D01*
X392011Y-292545D01*
X391199Y-287954D01*
X391930Y-286913D01*
X407817Y-284111D01*
X409174Y-282174D01*
X408173Y-276504D01*
X406234Y-275147D01*
X392836Y-277509D01*
X391793Y-276779D01*
X390983Y-272188D01*
X391713Y-271148D01*
X407884Y-268296D01*
X409242Y-266359D01*
X408242Y-260687D01*
X406302Y-259332D01*
X392844Y-261704D01*
X391801Y-260974D01*
X390991Y-256383D01*
X391721Y-255342D01*
X407730Y-252518D01*
X409085Y-250582D01*
X408085Y-244912D01*
X406146Y-243555D01*
X393116Y-245853D01*
X392075Y-245123D01*
X391262Y-240520D01*
X391983Y-239492D01*
X408141Y-236643D01*
X409499Y-234705D01*
X408498Y-229034D01*
X406560Y-227678D01*
X392861Y-230094D01*
X391820Y-229364D01*
X391008Y-224775D01*
X391741Y-223732D01*
X408080Y-220849D01*
X409436Y-218913D01*
X408435Y-213244D01*
X406498Y-211887D01*
X393013Y-214263D01*
X391971Y-213534D01*
X391160Y-208944D01*
X391161Y-208943D01*
Y-208944D01*
X391891Y-207902D01*
X408229Y-205020D01*
X409586Y-203084D01*
X408586Y-197412D01*
X406646Y-196057D01*
X393060Y-198452D01*
X392020Y-197722D01*
X391209Y-193132D01*
X391939Y-192090D01*
X408026Y-189253D01*
X409384Y-187315D01*
X408383Y-181644D01*
X406446Y-180287D01*
X393108Y-182640D01*
X392067Y-181910D01*
X391256Y-177321D01*
X391257Y-177320D01*
X391987Y-176278D01*
X408009Y-173451D01*
X409366Y-171514D01*
X408365Y-165844D01*
X406428Y-164487D01*
X392921Y-166869D01*
X391880Y-166139D01*
X391069Y-161549D01*
X391799Y-160507D01*
X407623Y-157715D01*
X408980Y-155778D01*
X407979Y-150108D01*
X406041Y-148752D01*
X393214Y-151014D01*
X392173Y-150284D01*
X391362Y-145695D01*
X391363Y-145694D01*
X392093Y-144653D01*
X395621Y-144028D01*
X398349Y-141300D01*
X399390Y-135393D01*
Y-122111D01*
X400480Y-121021D01*
G01X451000Y304000D02*
X447110D01*
X446660Y303550D01*
Y296202D01*
X444987Y294529D01*
X415100D01*
X414200Y293629D01*
Y290479D01*
X415100Y289579D01*
X477077D01*
X478750Y287906D01*
Y283662D01*
X477077Y281989D01*
X419550D01*
X418650Y281089D01*
Y277939D01*
X419550Y277039D01*
X477077D01*
X478750Y275366D01*
Y271122D01*
X477077Y269449D01*
X421610D01*
X420710Y268549D01*
Y265399D01*
X421610Y264499D01*
X477077D01*
X478750Y262826D01*
Y258582D01*
X477077Y256909D01*
X421670D01*
X420770Y256009D01*
Y252859D01*
X421670Y251959D01*
X477077D01*
X478750Y250286D01*
Y246042D01*
X477077Y244369D01*
X421610D01*
X420710Y243469D01*
Y240319D01*
X421610Y239419D01*
X444987D01*
X446660Y237746D01*
Y230450D01*
X447110Y230000D01*
X451000D01*
G01X441000Y304000D02*
X444890D01*
X445340Y303550D01*
Y296749D01*
X444440Y295849D01*
X414553D01*
X412880Y294176D01*
Y289932D01*
X414553Y288259D01*
X476530D01*
X477430Y287359D01*
Y284209D01*
X476530Y283309D01*
X419003D01*
X417330Y281636D01*
Y277392D01*
X419003Y275719D01*
X476530D01*
X477430Y274819D01*
Y271669D01*
X476530Y270769D01*
X421063D01*
X419390Y269096D01*
Y264852D01*
X421063Y263179D01*
X476530D01*
X477430Y262279D01*
Y259129D01*
X476530Y258229D01*
X421123D01*
X419450Y256556D01*
Y252312D01*
X421123Y250639D01*
X476530D01*
X477430Y249739D01*
Y246589D01*
X476530Y245689D01*
X421063D01*
X419390Y244016D01*
Y239772D01*
X421063Y238099D01*
X444440D01*
X445340Y237199D01*
Y230450D01*
X444890Y230000D01*
X441000D01*
G54D11*
X3000Y8494D03*
Y28494D03*
Y48494D03*
Y68494D03*
Y88494D03*
Y108494D03*
Y128494D03*
Y148494D03*
Y168494D03*
Y188494D03*
Y208494D03*
Y228494D03*
Y248494D03*
Y268494D03*
Y288494D03*
Y308494D03*
Y342126D03*
Y362126D03*
Y382126D03*
Y402126D03*
Y422126D03*
Y442126D03*
X18000Y240900D03*
Y237900D03*
Y249900D03*
Y246900D03*
Y243900D03*
X13827Y325310D03*
X14000Y401700D03*
Y406700D03*
Y404200D03*
X14700Y425000D03*
X22218Y3000D03*
X31920Y186610D03*
X21135Y236587D03*
X21205Y232767D03*
X21135Y240667D03*
Y243737D03*
X24690Y246467D03*
Y251967D03*
X21135Y246837D03*
X21035Y249937D03*
X24690Y249267D03*
X30638Y311957D03*
Y309068D03*
X31300Y329900D03*
X26300Y374400D03*
X31600Y379600D03*
X32700Y395381D03*
X25202Y425329D03*
X29400Y430900D03*
X23677Y422419D03*
X32100Y432800D03*
X20225Y447671D03*
X22692Y466518D03*
X42218Y3000D03*
X45500Y92500D03*
X47294Y184491D03*
X36599Y189016D03*
X37360Y194050D03*
X37823Y198346D03*
X47948Y201000D03*
X39900Y211000D03*
X39567Y243133D03*
X40500Y236900D03*
X41574Y255937D03*
X48420Y321616D03*
X39100Y321600D03*
X35500Y340500D03*
Y335000D03*
X44220Y341008D03*
X44500Y344000D03*
Y351600D03*
X35900Y363025D03*
X37800Y371225D03*
X44525Y364000D03*
Y368000D03*
Y384000D03*
X37020Y385600D03*
X36911Y394915D03*
X37067Y398337D03*
X43600Y422800D03*
X48050Y436350D03*
X40848Y448440D03*
X62218Y3000D03*
X53600Y44100D03*
X56348Y36210D03*
X55000Y76000D03*
X53400Y102788D03*
X59945Y120630D03*
X61123Y133070D03*
X52050Y208760D03*
X64050Y201010D03*
X52948Y200700D03*
X58823Y213531D03*
X51600Y241200D03*
X51010Y233570D03*
X50700Y250400D03*
X61200Y282600D03*
X58900Y288075D03*
X54660Y311660D03*
X60561Y314843D03*
X52820Y325200D03*
X55294Y369729D03*
X52475Y364000D03*
X58620Y408779D03*
X63200Y408600D03*
X72044Y132312D03*
X71970Y135893D03*
X69195Y135799D03*
X69285Y132321D03*
X68335Y141369D03*
X68375Y144100D03*
X68434Y149506D03*
X68432Y152147D03*
X72300Y159400D03*
X73550Y166680D03*
X71124Y178565D03*
X71146Y186489D03*
X71370Y188993D03*
X67386Y191935D03*
X67486Y188977D03*
X74046Y186490D03*
X71600Y200900D03*
X72150Y204810D03*
X76670Y208772D03*
X72500Y214000D03*
X70453Y222900D03*
X73011Y246365D03*
X68800Y253300D03*
X77437Y262760D03*
X78600Y283970D03*
X65100Y282475D03*
X75870Y290700D03*
X78770Y290708D03*
X75300Y305150D03*
X68500Y325100D03*
X78700Y340000D03*
X77860Y408678D03*
X69139Y413452D03*
X66319Y413492D03*
X74782Y413800D03*
X67000Y408800D03*
X69700D03*
X69030Y422653D03*
X71200Y431700D03*
X77600Y431400D03*
X79010Y445750D03*
X72800Y437900D03*
X82218Y3000D03*
X88000Y66500D03*
X88500Y128000D03*
X89170Y141540D03*
X80788Y190812D03*
X82370Y197010D03*
X91300Y252900D03*
X80300Y243700D03*
X83500Y266900D03*
X84016Y258230D03*
X91500Y267000D03*
X92300Y282100D03*
X81864Y297900D03*
X85600Y298100D03*
X82200Y308700D03*
X82022Y303350D03*
X84126Y311790D03*
X79600Y312000D03*
X85500Y326700D03*
X96030Y409400D03*
X81552Y409660D03*
X93259Y424200D03*
X81990Y448085D03*
X85490D03*
X102218Y3000D03*
X107000Y44500D03*
X102190Y63225D03*
Y66725D03*
X107124Y71004D03*
X104425Y82500D03*
X110950Y82050D03*
X111075Y104600D03*
X102999Y131799D03*
X95944Y149687D03*
X103580Y237400D03*
X106600Y253689D03*
X107200Y265000D03*
X106574Y280028D03*
X106100Y282900D03*
X100700Y293600D03*
X108551Y294241D03*
X99990Y311200D03*
Y307900D03*
X94400Y311100D03*
Y307200D03*
X95060Y327625D03*
X106852Y323292D03*
X103180Y336286D03*
X108500Y408680D03*
X95845Y424755D03*
X106700Y447730D03*
X122218Y3000D03*
X115000Y44500D03*
X112800Y60400D03*
X109121Y69500D03*
X123710Y82300D03*
X120724Y108937D03*
X109670Y136060D03*
X115400Y159500D03*
X123120Y213088D03*
X123790Y227656D03*
X123690Y230156D03*
X117840Y242200D03*
X121200Y234890D03*
X112900Y239200D03*
X122876Y245300D03*
X120020Y254430D03*
X119105Y251511D03*
X109800Y264928D03*
X111600Y262730D03*
Y284000D03*
X120070Y273700D03*
X115000D03*
X120600Y293471D03*
X124935Y324900D03*
X115600Y337900D03*
X114700Y351200D03*
X121200Y359200D03*
X111460Y361770D03*
X111950Y371200D03*
X122047Y372260D03*
X125650Y368650D03*
X111869Y365454D03*
X119200Y389700D03*
X110900Y378500D03*
X123100Y390600D03*
X122600Y394600D03*
X119026Y393332D03*
X116632Y411500D03*
X121700Y424005D03*
X133000Y59900D03*
X129500Y91475D03*
X134400Y127652D03*
X138458Y146458D03*
X132500Y167300D03*
X135300Y175100D03*
X125700Y183700D03*
X124338Y204742D03*
X124779Y201633D03*
X135000Y221200D03*
X132500Y221900D03*
X130167Y234733D03*
X128900Y255898D03*
X128760Y273701D03*
X137083Y278045D03*
X138600Y295900D03*
X124100Y311100D03*
X136100Y334000D03*
X129800Y325800D03*
X125900Y337600D03*
X133300Y334100D03*
X132600Y350090D03*
X124350Y352450D03*
X129776Y374500D03*
X138700Y376600D03*
X135300Y399900D03*
X129135Y410250D03*
X134300Y416414D03*
X128866Y433066D03*
X135350Y433016D03*
X124500Y424005D03*
X132070Y433110D03*
X125930D03*
X142218Y3000D03*
X145000Y90700D03*
X141100Y86500D03*
X151800Y116500D03*
X149800Y138100D03*
Y135100D03*
X152556Y147683D03*
X148429Y147682D03*
X144500Y169570D03*
X140903Y199421D03*
X143742Y203395D03*
X145500Y227700D03*
X149862Y243788D03*
X142085Y230549D03*
X151040Y237870D03*
X142780Y266830D03*
X152400Y284400D03*
X150293Y302117D03*
X147500Y289405D03*
X142300Y336700D03*
X144800D03*
X144700Y334100D03*
X150900Y360325D03*
X149500Y356700D03*
X141000Y358500D03*
X145703Y370700D03*
X139200Y372510D03*
X149000Y383070D03*
X152100Y378400D03*
X152500Y382600D03*
X150820Y387325D03*
X139400Y392460D03*
X153079Y412000D03*
X140600Y412300D03*
X162218Y3000D03*
X166200Y105500D03*
X162594Y212585D03*
Y210085D03*
X166140Y205955D03*
X165381Y201274D03*
X162653Y218843D03*
X159643Y226484D03*
X162200Y221376D03*
X163500Y229184D03*
X167200Y222600D03*
X157200Y240000D03*
X163690Y268610D03*
X168392Y298493D03*
X168300Y301100D03*
X162100Y291600D03*
X161400Y307600D03*
X164500Y314800D03*
X155000Y321100D03*
X161154Y376704D03*
X156300Y376300D03*
X154500Y387350D03*
X165500Y386000D03*
X165501Y382800D03*
X158200Y381400D03*
X160540Y416912D03*
X156101Y425100D03*
X163700Y422119D03*
X160700Y445550D03*
X182218Y3000D03*
X176900Y14625D03*
X179900Y91300D03*
X174600Y114000D03*
X182103Y132294D03*
X176550Y125210D03*
X174436Y132394D03*
X175300Y240000D03*
X174400Y249136D03*
X179846Y255150D03*
X180458Y258825D03*
X182232Y296424D03*
X174232Y304333D03*
X176563Y310917D03*
X170550Y304050D03*
X169077Y308677D03*
X170561Y306631D03*
X182700Y342216D03*
X177500Y369100D03*
X193100Y69100D03*
X189400Y69600D03*
X187400Y101500D03*
X186891Y113991D03*
X191482Y129294D03*
X195983D03*
X184000Y140500D03*
X189700Y140400D03*
X185897Y249936D03*
X191583Y261363D03*
X193386Y269142D03*
X184200Y264900D03*
X195031Y307182D03*
X197155Y314223D03*
X188546Y326356D03*
X190465Y344426D03*
X194800Y341700D03*
X197450Y356560D03*
X191420Y354710D03*
X190965Y348090D03*
X197400Y367600D03*
Y370250D03*
X197660Y390870D03*
X190050Y389140D03*
X189054Y397500D03*
X194500Y402600D03*
X195800Y396780D03*
X197600Y415400D03*
X195300Y432327D03*
X185000Y454000D03*
X191780Y453300D03*
X202218Y3000D03*
X209142Y53664D03*
X208200Y111760D03*
X204120Y132294D03*
X200000Y128764D03*
X212727Y132154D03*
X203542Y213254D03*
X200680Y257540D03*
X203090Y269229D03*
X205590Y269129D03*
X213258Y273265D03*
X204560Y301130D03*
X199729Y314565D03*
X200300Y328800D03*
X208000Y373240D03*
X200000Y407040D03*
X202513Y434800D03*
X199000Y444500D03*
X205200Y445400D03*
X222218Y3000D03*
X224000Y74275D03*
X224330Y83210D03*
X224958Y107236D03*
X230196Y267477D03*
X219900Y267100D03*
X227232Y270539D03*
X226500Y273000D03*
X216384Y312216D03*
X226100Y325065D03*
X221000Y343800D03*
X228230Y340040D03*
X221000Y352000D03*
X226710Y364815D03*
X223420Y367080D03*
X222575Y387625D03*
X217390Y401340D03*
X220134Y400780D03*
X226830Y435170D03*
X225000Y433100D03*
X219250Y422150D03*
X224000Y449100D03*
X242218Y3000D03*
X237000Y47200D03*
X240000Y67400D03*
X239660Y91920D03*
X233511Y132594D03*
X234500Y293500D03*
X242700Y306800D03*
X228800Y305500D03*
X243010Y323400D03*
X230445Y325945D03*
X235000Y335300D03*
X233500Y346911D03*
Y343911D03*
X233650Y359628D03*
X233800Y354300D03*
X232470Y382280D03*
X233600Y377300D03*
X233790Y384490D03*
X236670Y394550D03*
X229900Y436600D03*
X236900Y440565D03*
X241436Y445784D03*
X244208Y97302D03*
X247200Y117400D03*
X245310Y113910D03*
X252639Y247885D03*
X255700Y260000D03*
X247923Y319000D03*
X256124Y336355D03*
X244790Y375910D03*
X248800Y385700D03*
X249400Y410300D03*
X257810Y435100D03*
X262218Y3000D03*
X263102Y91725D03*
X269493Y138604D03*
X260388Y125001D03*
X272300Y251000D03*
X258628Y247600D03*
X266600Y268700D03*
X266300Y307500D03*
X264265Y315817D03*
X261300Y334100D03*
X259420Y343230D03*
Y340630D03*
X265100Y395100D03*
X261700Y439700D03*
X269561Y456044D03*
X282218Y3000D03*
X290000Y82000D03*
X287578Y84092D03*
X278300Y95019D03*
X274760Y105140D03*
X280910Y102880D03*
X274200Y109500D03*
X275960Y126010D03*
X273450Y125050D03*
X285899Y153542D03*
X283399D03*
X276200Y251500D03*
X280082Y251328D03*
X280030Y267098D03*
Y264098D03*
X284357Y267027D03*
Y264027D03*
X287507Y301596D03*
X281300Y308800D03*
X287050Y305850D03*
X289939Y309060D03*
X273355Y330001D03*
X286372Y320700D03*
X289600Y322253D03*
X286372Y326768D03*
X277500Y348469D03*
X276145Y366455D03*
X276400Y370400D03*
X283664Y379236D03*
X273100Y381500D03*
X283973Y382553D03*
X285191Y390840D03*
X287630Y389378D03*
X287476Y396680D03*
X281300Y416200D03*
X278409Y433722D03*
X276400Y431810D03*
X302218Y3000D03*
X297466Y51521D03*
X297575Y73738D03*
X293773Y73530D03*
X298575Y101900D03*
X298975Y118900D03*
X301000Y121016D03*
X300500Y125000D03*
X295075Y119100D03*
X301000Y129900D03*
X301120Y235626D03*
Y238765D03*
X302687Y275497D03*
X291500Y287670D03*
Y285170D03*
X291000Y297700D03*
X291300Y315900D03*
X301500Y326500D03*
X290120Y339370D03*
X290000Y335600D03*
X300700Y341300D03*
X296780Y371500D03*
X298152Y393332D03*
X292700Y403700D03*
X295729Y453912D03*
Y456912D03*
Y459912D03*
X297738Y452418D03*
Y458418D03*
Y455418D03*
X315100Y116400D03*
X313800Y124300D03*
X317110Y219140D03*
X309521Y235352D03*
Y238741D03*
X307800Y259200D03*
X312114Y288439D03*
X315810Y293450D03*
X312315Y293207D03*
X317430Y295665D03*
X314820Y296128D03*
X314201Y302361D03*
X314180Y299440D03*
X303077Y297519D03*
X314132Y310178D03*
X314170Y307020D03*
X309500Y315000D03*
X304000Y305000D03*
X303000Y309200D03*
X311000Y320500D03*
X312300Y340700D03*
X311925Y366475D03*
X308926Y401900D03*
X314969Y456527D03*
X322218Y3000D03*
X321800Y60055D03*
X320765Y114582D03*
X331405Y167411D03*
Y172411D03*
X320054Y195163D03*
Y198663D03*
X317922Y238717D03*
Y235328D03*
X326323Y235304D03*
Y238693D03*
X317670Y291430D03*
X330900Y314700D03*
X325593Y406500D03*
X329093D03*
X318593D03*
X322093D03*
X331646Y466536D03*
X342218Y3000D03*
X339939Y162911D03*
X339812Y173380D03*
X339800Y182926D03*
X337400Y193449D03*
X334724Y238669D03*
Y235280D03*
X337467Y236984D03*
X336312Y286352D03*
X342604Y318773D03*
X345500Y342690D03*
X335475Y367500D03*
X334112Y447668D03*
X351331Y20788D03*
Y40788D03*
Y60788D03*
Y80788D03*
Y100788D03*
Y120788D03*
Y140788D03*
Y160788D03*
Y180788D03*
Y200788D03*
Y220788D03*
Y240788D03*
Y260788D03*
Y280788D03*
Y300788D03*
X349290Y337646D03*
X351331Y357531D03*
Y377531D03*
Y397531D03*
Y417531D03*
Y437531D03*
X375904Y-438145D03*
X375964Y-215959D03*
X379304Y-438145D03*
X379364Y-215959D03*
X396992Y-464207D03*
X400392D03*
X397080Y-121021D03*
X400480D03*
G54D21*
G01X132600Y350090D02*
X127990Y354700D01*
X122500D01*
X119000Y351200D01*
X114700D01*
G54D12*
G01X55000Y76000D02*
Y73297D01*
X58297Y70000D01*
X77500D01*
X78500Y69000D01*
X86500D01*
X88000Y67500D01*
Y66500D01*
G01X61123Y133070D02*
X64000Y130193D01*
Y111631D01*
X61400Y105354D01*
Y91801D01*
X71956Y81245D01*
X95456D01*
X101071Y86860D01*
X110573D01*
X115513Y91800D01*
X122411D01*
X126616Y87595D01*
X134026D01*
X139086Y82535D01*
X143143D01*
X145968Y83705D01*
X148129Y84600D01*
X152905Y89376D01*
Y97172D01*
X159058Y103325D01*
X164025D01*
X166200Y105500D01*
G01X115000Y44500D02*
Y35500D01*
X111400Y31900D01*
Y22000D01*
X114800Y18600D01*
X172425D01*
X176400Y14625D01*
X176900D01*
G01X237000Y47200D02*
X225500Y35700D01*
X211100D01*
X190025Y14625D01*
X176900D01*
G01X174232Y304333D02*
X174665Y303900D01*
X177334D01*
X179556Y304820D01*
X187120D01*
X188000Y305700D01*
X194030D01*
X195031Y306701D01*
Y307182D01*
G01X278982Y123882D02*
X279964Y122900D01*
G01D02*
X290200D01*
X291900Y121200D01*
Y83900D01*
X290000Y82000D01*
X65607Y359023D03*
X81355Y346425D03*
X75056Y362173D03*
X71906Y371584D03*
X68757D03*
X71906Y374733D03*
X90766Y355873D03*
X87617D03*
X90766Y359023D03*
X87617D03*
X90766Y377883D03*
X87617Y390481D03*
Y387332D03*
X90766Y381033D03*
X87617Y377883D03*
X90766Y390481D03*
Y387332D03*
X92360Y394175D03*
X89210D03*
X93916Y349574D03*
X106515Y352724D03*
X106514Y349574D03*
X93916Y355873D03*
Y381033D03*
Y387332D03*
X175196Y159748D03*
X184645Y181795D03*
X174569Y180202D03*
X175196Y172347D03*
X173000Y170200D03*
X175196Y200655D03*
X181495Y219553D03*
X184645D03*
X194094Y169197D03*
X190944Y178646D03*
Y181795D03*
X184645Y178646D03*
Y169197D03*
Y172347D03*
X187794Y184945D03*
X184645Y197506D03*
X190944Y210104D03*
Y203805D03*
X187794Y210104D03*
Y222703D03*
X194094Y229002D03*
X197243D03*
Y232151D03*
X206692Y166047D03*
X212991D03*
X209842Y169197D03*
X203542Y175496D03*
X206692D03*
X209842D03*
X200393Y213254D03*
Y219553D03*
X209842Y225852D03*
Y222703D03*
X225552Y181795D03*
X228739Y222703D03*
X222440D03*
X228702Y181795D03*
Y178646D03*
X244450Y200655D03*
X231851Y210104D03*
X228702D03*
X228739Y216441D03*
X250749Y169197D03*
X253898D03*
X244450Y181795D03*
X250749Y175496D03*
X244450D03*
X250749Y172347D03*
X253898Y175496D03*
X247599Y184945D03*
X257048Y191244D03*
X244450Y184945D03*
X247599Y206955D03*
Y210104D03*
X250749Y206955D03*
Y210104D03*
X257048Y213254D03*
X250749D03*
X247599D03*
X253898D03*
X267722Y176791D03*
X264222D03*
X271209Y177524D03*
X270472Y188488D03*
X263580Y214593D03*
X267080D03*
X273644Y174267D03*
X295410Y169786D03*
X292404Y176085D03*
X295410Y179235D03*
X289254Y176085D03*
Y182385D03*
X295411Y185534D03*
X298714Y210477D03*
X292404Y210587D03*
Y201282D03*
Y213737D03*
X289254Y201139D03*
X308008Y166637D03*
X305002Y176085D03*
Y169786D03*
Y172936D03*
X308152Y169786D03*
Y172936D03*
Y182385D03*
X305002Y179235D03*
X308008Y185391D03*
Y207438D03*
X308152Y204432D03*
X305002D03*
X311158Y210587D03*
X308008Y210731D03*
X305002Y210587D03*
G54D13*
X155205Y52677D03*
G54D14*
X451000Y-215000D03*
X441000D03*
Y-136600D03*
X451000D03*
Y230000D03*
X441000D03*
Y304000D03*
X451000D03*
G54D15*
G01X104425Y82500D02*
X106801D01*
X109801Y79500D01*
X112311D01*
X112995Y80184D01*
X119984D01*
X122100Y82300D01*
X123710D01*
G01X128900Y255898D02*
X126702D01*
X124700Y257900D01*
X114700D01*
X113500Y259100D01*
X106000D01*
X104200Y260900D01*
Y262076D01*
X100250Y266026D01*
Y267974D01*
X101626Y269350D01*
X107150D01*
X109100Y271300D01*
X132800D01*
X137385Y266715D01*
X142665D01*
X142780Y266830D01*
G01X132500Y167300D02*
Y164900D01*
X128600Y161000D01*
X116900D01*
X115400Y159500D01*
G01X174400Y249136D02*
X172007D01*
X171328Y249815D01*
X152835D01*
X150565Y252085D01*
X133315D01*
X129502Y255898D01*
X128900D01*
G01X163700Y422119D02*
Y424399D01*
X157433Y430666D01*
X134294D01*
X132070Y432890D01*
Y433110D01*
G01X163690Y268610D02*
X163387Y268307D01*
X162606D01*
X160799Y266500D01*
X154000D01*
X151700Y264200D01*
X147900D01*
X145400Y266700D01*
X143215D01*
X143085Y266830D01*
X142780D01*
G01X204560Y301130D02*
X203850Y300420D01*
Y295394D01*
X197656Y289200D01*
X167824D01*
X163050Y293974D01*
X160674D01*
X152400Y285700D01*
Y284400D01*
G01X163690Y268610D02*
X164980Y269900D01*
X166099D01*
X170137Y265862D01*
X179362D01*
X181700Y268200D01*
X185640D01*
X191583Y262257D01*
Y261363D01*
G01X185897Y249936D02*
X185097Y249136D01*
X174400D01*
G01X191583Y261363D02*
X190120Y259900D01*
Y254159D01*
X185897Y249936D01*
G01X303000Y309200D02*
X302375Y308575D01*
X301575D01*
X296000Y303000D01*
Y267000D01*
X303800Y259200D01*
X307800D01*
G54D16*
G01X106515Y352724D02*
X104915Y354324D01*
X93335D01*
X91786Y355873D01*
X90766D01*
G01X106514Y349574D02*
X104927Y351161D01*
X93350D01*
X92411Y352100D01*
Y353390D01*
X91433Y354368D01*
X90132D01*
X88627Y355873D01*
X87617D01*
G01X111869Y365454D02*
X109554D01*
X104644Y360544D01*
X92287D01*
X90766Y359023D01*
G01X111460Y361770D02*
X110276Y362954D01*
X108855D01*
X103472Y357571D01*
X95614D01*
X93916Y355873D01*
G54D17*
G01X2010999Y-388000D02*
Y1475775D01*
X-407000D01*
Y-386798D01*
Y-755294D01*
Y-793716D01*
X-368578D01*
X1942346D01*
X2010999D01*
Y-725063D01*
Y-388000D01*
G01X-53307Y-609436D02*
Y-684436D01*
X446693D01*
Y-609436D01*
X-53307D01*
G01X-41307Y-674436D02*
Y-679436D01*
G01X-42764Y-674436D02*
X-39850D01*
G01X-34940Y-679436D02*
X-37474D01*
Y-674436D01*
X-34940D01*
G01X-35954Y-676853D02*
X-37474D01*
G01X-32374Y-674436D02*
Y-679436D01*
X-29840D01*
G01X-26007Y-679603D02*
X-26134Y-679519D01*
Y-679353D01*
X-26007Y-679269D01*
X-25880Y-679353D01*
Y-679519D01*
X-26007Y-679603D01*
G01Y-677353D02*
X-26134Y-677269D01*
Y-677103D01*
X-26007Y-677019D01*
X-25880Y-677103D01*
Y-677269D01*
X-26007Y-677353D01*
G01X-21224Y-681103D02*
X-21857Y-680269D01*
X-22174Y-679436D01*
Y-676103D01*
X-21857Y-675269D01*
X-21224Y-674436D01*
G01X-15807D02*
X-16314Y-674603D01*
X-16694Y-675019D01*
X-16947Y-675519D01*
X-17137Y-676186D01*
X-17200Y-676936D01*
X-17137Y-677686D01*
X-16947Y-678353D01*
X-16694Y-678853D01*
X-16314Y-679269D01*
X-15807Y-679436D01*
X-15300Y-679269D01*
X-14920Y-678853D01*
X-14667Y-678353D01*
X-14477Y-677686D01*
X-14414Y-676936D01*
X-14477Y-676186D01*
X-14667Y-675519D01*
X-14920Y-675019D01*
X-15300Y-674603D01*
X-15807Y-674436D01*
G01X-12100Y-678436D02*
X-11720Y-679019D01*
X-11214Y-679353D01*
X-10644Y-679436D01*
X-10137Y-679353D01*
X-9630Y-678936D01*
X-9314Y-678436D01*
X-9250Y-677936D01*
X-9377Y-677353D01*
X-9820Y-676936D01*
X-10264Y-676769D01*
X-10834D01*
G01X-10264D02*
X-9884Y-676519D01*
X-9567Y-676103D01*
X-9440Y-675603D01*
X-9567Y-675103D01*
X-9884Y-674686D01*
X-10454Y-674436D01*
X-11024Y-674519D01*
X-11594Y-674853D01*
G01X-5290Y-681103D02*
X-4657Y-680269D01*
X-4340Y-679436D01*
Y-676103D01*
X-4657Y-675269D01*
X-5290Y-674436D01*
G01X-1900Y-678436D02*
X-1520Y-679019D01*
X-1014Y-679353D01*
X-444Y-679436D01*
X63Y-679353D01*
X570Y-678936D01*
X886Y-678436D01*
X950Y-677936D01*
X823Y-677353D01*
X380Y-676936D01*
X-64Y-676769D01*
X-634D01*
G01X-64D02*
X316Y-676519D01*
X633Y-676103D01*
X760Y-675603D01*
X633Y-675103D01*
X316Y-674686D01*
X-254Y-674436D01*
X-824Y-674519D01*
X-1394Y-674853D01*
G01X3390Y-675269D02*
X3770Y-674769D01*
X4213Y-674519D01*
X4720Y-674436D01*
X5353Y-674603D01*
X5796Y-675019D01*
X5923Y-675519D01*
X5860Y-676019D01*
X5606Y-676436D01*
X4340Y-677269D01*
X3770Y-677853D01*
X3390Y-678686D01*
X3263Y-679436D01*
X5923D01*
G01X9566D02*
X9693Y-678353D01*
X9883Y-677436D01*
X10136Y-676603D01*
X10453Y-675686D01*
X10960Y-674436D01*
X8426D01*
G01X13970Y-677769D02*
X15616D01*
G01X18690Y-675269D02*
X19070Y-674769D01*
X19513Y-674519D01*
X20020Y-674436D01*
X20653Y-674603D01*
X21096Y-675019D01*
X21223Y-675519D01*
X21160Y-676019D01*
X20906Y-676436D01*
X19640Y-677269D01*
X19070Y-677853D01*
X18690Y-678686D01*
X18563Y-679436D01*
X21223D01*
G01X23600Y-678436D02*
X23980Y-679019D01*
X24486Y-679353D01*
X25056Y-679436D01*
X25563Y-679353D01*
X26070Y-678936D01*
X26386Y-678436D01*
X26450Y-677936D01*
X26323Y-677353D01*
X25880Y-676936D01*
X25436Y-676769D01*
X24866D01*
G01X25436D02*
X25816Y-676519D01*
X26133Y-676103D01*
X26260Y-675603D01*
X26133Y-675103D01*
X25816Y-674686D01*
X25246Y-674436D01*
X24676Y-674519D01*
X24106Y-674853D01*
G01X30853Y-679436D02*
Y-674436D01*
X28510Y-678019D01*
X31676D01*
G01X33800Y-678686D02*
X34180Y-679103D01*
X34623Y-679353D01*
X35193Y-679436D01*
X35763Y-679269D01*
X36206Y-678936D01*
X36523Y-678353D01*
X36586Y-677686D01*
X36460Y-677019D01*
X36143Y-676603D01*
X35700Y-676269D01*
X35256Y-676186D01*
X34813Y-676269D01*
X34243Y-676603D01*
X34433Y-674436D01*
X36143D01*
G01X44190Y-679436D02*
Y-674436D01*
X46596D01*
G01X45710Y-676853D02*
X44190D01*
G01X48910Y-679436D02*
X50493Y-674436D01*
X52076Y-679436D01*
G01X51506Y-677686D02*
X49480D01*
G01X54263Y-679436D02*
X56923Y-674436D01*
G01X54263D02*
X56923Y-679436D01*
G01X60693Y-679603D02*
X60566Y-679519D01*
Y-679353D01*
X60693Y-679269D01*
X60820Y-679353D01*
Y-679519D01*
X60693Y-679603D01*
G01Y-677353D02*
X60566Y-677269D01*
Y-677103D01*
X60693Y-677019D01*
X60820Y-677103D01*
Y-677269D01*
X60693Y-677353D01*
G01X65476Y-681103D02*
X64843Y-680269D01*
X64526Y-679436D01*
Y-676103D01*
X64843Y-675269D01*
X65476Y-674436D01*
G01X70893D02*
X70386Y-674603D01*
X70006Y-675019D01*
X69753Y-675519D01*
X69563Y-676186D01*
X69500Y-676936D01*
X69563Y-677686D01*
X69753Y-678353D01*
X70006Y-678853D01*
X70386Y-679269D01*
X70893Y-679436D01*
X71400Y-679269D01*
X71780Y-678853D01*
X72033Y-678353D01*
X72223Y-677686D01*
X72286Y-676936D01*
X72223Y-676186D01*
X72033Y-675519D01*
X71780Y-675019D01*
X71400Y-674603D01*
X70893Y-674436D01*
G01X74600Y-678436D02*
X74980Y-679019D01*
X75486Y-679353D01*
X76056Y-679436D01*
X76563Y-679353D01*
X77070Y-678936D01*
X77386Y-678436D01*
X77450Y-677936D01*
X77323Y-677353D01*
X76880Y-676936D01*
X76436Y-676769D01*
X75866D01*
G01X76436D02*
X76816Y-676519D01*
X77133Y-676103D01*
X77260Y-675603D01*
X77133Y-675103D01*
X76816Y-674686D01*
X76246Y-674436D01*
X75676Y-674519D01*
X75106Y-674853D01*
G01X81410Y-681103D02*
X82043Y-680269D01*
X82360Y-679436D01*
Y-676103D01*
X82043Y-675269D01*
X81410Y-674436D01*
G01X84800Y-678436D02*
X85180Y-679019D01*
X85686Y-679353D01*
X86256Y-679436D01*
X86763Y-679353D01*
X87270Y-678936D01*
X87586Y-678436D01*
X87650Y-677936D01*
X87523Y-677353D01*
X87080Y-676936D01*
X86636Y-676769D01*
X86066D01*
G01X86636D02*
X87016Y-676519D01*
X87333Y-676103D01*
X87460Y-675603D01*
X87333Y-675103D01*
X87016Y-674686D01*
X86446Y-674436D01*
X85876Y-674519D01*
X85306Y-674853D01*
G01X90216Y-678853D02*
X90660Y-679269D01*
X91166Y-679436D01*
X91673Y-679269D01*
X92116Y-678769D01*
X92433Y-678019D01*
X92560Y-677269D01*
Y-676353D01*
X92433Y-675603D01*
X92116Y-674936D01*
X91736Y-674603D01*
X91293Y-674436D01*
X90786Y-674603D01*
X90406Y-674936D01*
X90153Y-675436D01*
X90026Y-676103D01*
X90153Y-676686D01*
X90470Y-677269D01*
X90850Y-677603D01*
X91293Y-677686D01*
X91800Y-677519D01*
X92180Y-677103D01*
X92560Y-676353D01*
G01X96266Y-679436D02*
X96393Y-678353D01*
X96583Y-677436D01*
X96836Y-676603D01*
X97153Y-675686D01*
X97660Y-674436D01*
X95126D01*
G01X100670Y-677769D02*
X102316D01*
G01X105200Y-678436D02*
X105580Y-679019D01*
X106086Y-679353D01*
X106656Y-679436D01*
X107163Y-679353D01*
X107670Y-678936D01*
X107986Y-678436D01*
X108050Y-677936D01*
X107923Y-677353D01*
X107480Y-676936D01*
X107036Y-676769D01*
X106466D01*
G01X107036D02*
X107416Y-676519D01*
X107733Y-676103D01*
X107860Y-675603D01*
X107733Y-675103D01*
X107416Y-674686D01*
X106846Y-674436D01*
X106276Y-674519D01*
X105706Y-674853D01*
G01X110490Y-677353D02*
X110933Y-676769D01*
X111313Y-676436D01*
X111820Y-676269D01*
X112263Y-676436D01*
X112580Y-676769D01*
X112833Y-677269D01*
X112896Y-677853D01*
X112833Y-678353D01*
X112580Y-678853D01*
X112200Y-679269D01*
X111756Y-679436D01*
X111250Y-679269D01*
X110806Y-678769D01*
X110553Y-678019D01*
X110490Y-677186D01*
X110616Y-676103D01*
X110806Y-675519D01*
X111123Y-674936D01*
X111566Y-674519D01*
X112010Y-674436D01*
X112453Y-674603D01*
X112770Y-675019D01*
G01X116793Y-679436D02*
Y-674436D01*
X116033Y-675436D01*
G01Y-679436D02*
X117553D01*
G01X122653D02*
Y-674436D01*
X120310Y-678019D01*
X123476D01*
G01X141693Y-609436D02*
Y-684436D01*
G01Y-659436D02*
X244693D01*
Y-634436D01*
G01X141693D02*
X244693D01*
G01X246693Y-609436D02*
Y-684436D01*
G01X244693Y-609436D02*
Y-684436D01*
G01X252200Y-669436D02*
Y-664436D01*
X253466D01*
X253973Y-664686D01*
X254353Y-665019D01*
X254670Y-665519D01*
X254923Y-666103D01*
X254986Y-666936D01*
X254923Y-667769D01*
X254670Y-668353D01*
X254353Y-668853D01*
X253973Y-669186D01*
X253466Y-669436D01*
X252200D01*
G01X257110D02*
X258693Y-664436D01*
X260276Y-669436D01*
G01X259706Y-667686D02*
X257680D01*
G01X263793Y-664436D02*
Y-669436D01*
G01X262336Y-664436D02*
X265250D01*
G01X270160Y-669436D02*
X267626D01*
Y-664436D01*
X270160D01*
G01X269146Y-666853D02*
X267626D01*
G01X273993Y-669603D02*
X273866Y-669519D01*
Y-669353D01*
X273993Y-669269D01*
X274120Y-669353D01*
Y-669519D01*
X273993Y-669603D01*
G01Y-667353D02*
X273866Y-667269D01*
Y-667103D01*
X273993Y-667019D01*
X274120Y-667103D01*
Y-667269D01*
X273993Y-667353D01*
G01X246693Y-659436D02*
X446693D01*
G01X252326Y-644436D02*
Y-639436D01*
X253846D01*
X254353Y-639686D01*
X254733Y-640269D01*
X254860Y-640936D01*
X254733Y-641603D01*
X254416Y-642103D01*
X253846Y-642353D01*
X252326D01*
G01X257553Y-644603D02*
X259833Y-639436D01*
G01X262336Y-644436D02*
Y-639436D01*
X265250Y-644436D01*
Y-639436D01*
G01X268893Y-644603D02*
X268766Y-644519D01*
Y-644353D01*
X268893Y-644269D01*
X269020Y-644353D01*
Y-644519D01*
X268893Y-644603D01*
G01Y-642353D02*
X268766Y-642269D01*
Y-642103D01*
X268893Y-642019D01*
X269020Y-642103D01*
Y-642269D01*
X268893Y-642353D01*
G01X246693Y-634436D02*
X446693D01*
G01X252326Y-619436D02*
Y-614436D01*
X253846D01*
X254353Y-614686D01*
X254733Y-615269D01*
X254860Y-615936D01*
X254733Y-616603D01*
X254416Y-617103D01*
X253846Y-617353D01*
X252326D01*
G01X257426Y-619436D02*
Y-614436D01*
X259010D01*
X259516Y-614686D01*
X259833Y-615019D01*
X259960Y-615686D01*
X259833Y-616353D01*
X259453Y-616769D01*
X259010Y-617019D01*
X257426D01*
G01X259010D02*
X259960Y-619436D01*
G01X263793D02*
X263286Y-619353D01*
X262843Y-619019D01*
X262463Y-618519D01*
X262210Y-617936D01*
X262083Y-617269D01*
Y-616603D01*
X262210Y-615936D01*
X262463Y-615353D01*
X262843Y-614853D01*
X263286Y-614519D01*
X263793Y-614436D01*
X264300Y-614519D01*
X264743Y-614853D01*
X265123Y-615353D01*
X265376Y-615936D01*
X265503Y-616603D01*
Y-617269D01*
X265376Y-617936D01*
X265123Y-618519D01*
X264743Y-619019D01*
X264300Y-619353D01*
X263793Y-619436D01*
G01X267626Y-618436D02*
X267943Y-618936D01*
X268323Y-619269D01*
X268766Y-619436D01*
X269273Y-619269D01*
X269653Y-618936D01*
X270033Y-618436D01*
X270160Y-617769D01*
Y-614436D01*
G01X275260Y-619436D02*
X272726D01*
Y-614436D01*
X275260D01*
G01X274246Y-616853D02*
X272726D01*
G01X280486Y-614853D02*
X280106Y-614603D01*
X279663Y-614436D01*
X279156D01*
X278586Y-614686D01*
X278143Y-615103D01*
X277826Y-615603D01*
X277573Y-616436D01*
X277510Y-617186D01*
X277636Y-617936D01*
X277826Y-618436D01*
X278206Y-618936D01*
X278650Y-619269D01*
X279093Y-619436D01*
X279536D01*
X279980Y-619269D01*
X280360Y-619019D01*
X280676Y-618686D01*
G01X284193Y-614436D02*
Y-619436D01*
G01X282736Y-614436D02*
X285650D01*
G01X289293Y-619603D02*
X289166Y-619519D01*
Y-619353D01*
X289293Y-619269D01*
X289420Y-619353D01*
Y-619519D01*
X289293Y-619603D01*
G01Y-617353D02*
X289166Y-617269D01*
Y-617103D01*
X289293Y-617019D01*
X289420Y-617103D01*
Y-617269D01*
X289293Y-617353D01*
G01X361693Y-659436D02*
Y-684436D01*
G01X364326Y-661936D02*
Y-666936D01*
X366860D01*
G01X369933Y-661936D02*
X371453D01*
G01X370693D02*
Y-666936D01*
G01X369933D02*
X371453D01*
G01X376300Y-664269D02*
X376553Y-664019D01*
X376743Y-663603D01*
X376870Y-663019D01*
X376743Y-662519D01*
X376490Y-662186D01*
X376046Y-661936D01*
X374336D01*
Y-666936D01*
X376426D01*
X376870Y-666603D01*
X377123Y-666103D01*
X377250Y-665519D01*
X377123Y-664936D01*
X376743Y-664436D01*
X376300Y-664269D01*
X374336D01*
G01X380893Y-667103D02*
X380766Y-667019D01*
Y-666853D01*
X380893Y-666769D01*
X381020Y-666853D01*
Y-667019D01*
X380893Y-667103D01*
G01Y-664853D02*
X380766Y-664769D01*
Y-664603D01*
X380893Y-664519D01*
X381020Y-664603D01*
Y-664769D01*
X380893Y-664853D01*
G01X404693Y-659436D02*
Y-684436D01*
G01Y-634436D02*
Y-659436D01*
G01X412706Y-687603D02*
X412813Y-687478D01*
X412893Y-687269D01*
X412946Y-686978D01*
X412893Y-686728D01*
X412786Y-686561D01*
X412600Y-686436D01*
X411880D01*
Y-688936D01*
X412760D01*
X412946Y-688769D01*
X413053Y-688519D01*
X413106Y-688228D01*
X413053Y-687936D01*
X412893Y-687686D01*
X412706Y-687603D01*
X411880D01*
G01X415173Y-688936D02*
Y-687269D01*
G01Y-687561D02*
X415066Y-687394D01*
X414906Y-687311D01*
X414720Y-687269D01*
X414533Y-687353D01*
X414373Y-687519D01*
X414266Y-687769D01*
X414213Y-688103D01*
X414266Y-688436D01*
X414373Y-688686D01*
X414533Y-688853D01*
X414720Y-688936D01*
X414906Y-688894D01*
X415066Y-688769D01*
X415173Y-688603D01*
G01X416493Y-688644D02*
X416626Y-688811D01*
X416813Y-688936D01*
X416973D01*
X417133Y-688853D01*
X417240Y-688728D01*
X417293Y-688561D01*
X417266Y-688311D01*
X417160Y-688186D01*
X416680Y-687936D01*
X416573Y-687644D01*
X416626Y-687436D01*
X416733Y-687311D01*
X416893Y-687269D01*
X417053Y-687311D01*
X417213Y-687436D01*
G01X418693Y-687811D02*
X419546D01*
X419466Y-687519D01*
X419333Y-687353D01*
X419146Y-687269D01*
X418960Y-687311D01*
X418800Y-687436D01*
X418693Y-687728D01*
X418640Y-687978D01*
Y-688228D01*
X418693Y-688478D01*
X418826Y-688728D01*
X418986Y-688894D01*
X419173Y-688936D01*
X419360Y-688853D01*
X419546Y-688603D01*
G01X420813Y-688936D02*
Y-686436D01*
G01Y-687686D02*
X420946Y-687436D01*
X421106Y-687311D01*
X421266Y-687269D01*
X421506Y-687353D01*
X421666Y-687519D01*
X421773Y-687811D01*
Y-688144D01*
X421720Y-688478D01*
X421613Y-688728D01*
X421426Y-688894D01*
X421266Y-688936D01*
X421106Y-688894D01*
X420946Y-688769D01*
X420813Y-688561D01*
G01X423493Y-688936D02*
X423333Y-688894D01*
X423173Y-688728D01*
X423066Y-688436D01*
X423013Y-688103D01*
X423066Y-687769D01*
X423173Y-687478D01*
X423333Y-687311D01*
X423493Y-687269D01*
X423653Y-687311D01*
X423813Y-687478D01*
X423920Y-687769D01*
X423946Y-688103D01*
X423920Y-688436D01*
X423813Y-688728D01*
X423653Y-688894D01*
X423493Y-688936D01*
G01X426173D02*
Y-687269D01*
G01Y-687561D02*
X426066Y-687394D01*
X425906Y-687311D01*
X425720Y-687269D01*
X425533Y-687353D01*
X425373Y-687519D01*
X425266Y-687769D01*
X425213Y-688103D01*
X425266Y-688436D01*
X425373Y-688686D01*
X425533Y-688853D01*
X425720Y-688936D01*
X425906Y-688894D01*
X426066Y-688769D01*
X426173Y-688603D01*
G01X427520Y-688936D02*
Y-687269D01*
G01Y-687603D02*
X427653Y-687436D01*
X427786Y-687311D01*
X427973Y-687269D01*
X428106Y-687311D01*
X428266Y-687436D01*
G01X430573Y-686436D02*
Y-688936D01*
G01Y-688561D02*
X430466Y-688769D01*
X430306Y-688894D01*
X430120Y-688936D01*
X429906Y-688853D01*
X429746Y-688644D01*
X429640Y-688394D01*
X429613Y-688103D01*
X429640Y-687811D01*
X429746Y-687561D01*
X429906Y-687353D01*
X430120Y-687269D01*
X430306Y-687311D01*
X430440Y-687394D01*
X430573Y-687561D01*
G01X433960Y-688936D02*
Y-686436D01*
X434626D01*
X434840Y-686561D01*
X434973Y-686728D01*
X435026Y-687061D01*
X434973Y-687394D01*
X434813Y-687603D01*
X434626Y-687728D01*
X433960D01*
G01X434626D02*
X435026Y-688936D01*
G01X436293Y-687811D02*
X437146D01*
X437066Y-687519D01*
X436933Y-687353D01*
X436746Y-687269D01*
X436560Y-687311D01*
X436400Y-687436D01*
X436293Y-687728D01*
X436240Y-687978D01*
Y-688228D01*
X436293Y-688478D01*
X436426Y-688728D01*
X436586Y-688894D01*
X436773Y-688936D01*
X436960Y-688853D01*
X437146Y-688603D01*
G01X438413Y-687269D02*
X438893Y-688936D01*
X439373Y-687269D01*
G01X441093Y-689019D02*
X441040Y-688978D01*
Y-688894D01*
X441093Y-688853D01*
X441146Y-688894D01*
Y-688978D01*
X441093Y-689019D01*
G01X443613Y-688936D02*
Y-686436D01*
X442626Y-688228D01*
X443960D01*
G01X444826Y-688936D02*
X445493Y-686436D01*
X446160Y-688936D01*
G01X445920Y-688061D02*
X445066D01*
G01X408593Y-661936D02*
Y-666936D01*
G01X407136Y-661936D02*
X410050D01*
G01X413693Y-666936D02*
X413313Y-666853D01*
X412933Y-666519D01*
X412680Y-665936D01*
X412553Y-665269D01*
X412680Y-664603D01*
X412933Y-664019D01*
X413313Y-663686D01*
X413693Y-663603D01*
X414073Y-663686D01*
X414453Y-664019D01*
X414706Y-664603D01*
X414770Y-665269D01*
X414706Y-665936D01*
X414453Y-666519D01*
X414073Y-666853D01*
X413693Y-666936D01*
G01X418793D02*
X418413Y-666853D01*
X418033Y-666519D01*
X417780Y-665936D01*
X417653Y-665269D01*
X417780Y-664603D01*
X418033Y-664019D01*
X418413Y-663686D01*
X418793Y-663603D01*
X419173Y-663686D01*
X419553Y-664019D01*
X419806Y-664603D01*
X419870Y-665269D01*
X419806Y-665936D01*
X419553Y-666519D01*
X419173Y-666853D01*
X418793Y-666936D01*
G01X423893D02*
Y-661936D01*
G01X428993Y-667103D02*
X428866Y-667019D01*
Y-666853D01*
X428993Y-666769D01*
X429120Y-666853D01*
Y-667019D01*
X428993Y-667103D01*
G01Y-664853D02*
X428866Y-664769D01*
Y-664603D01*
X428993Y-664519D01*
X429120Y-664603D01*
Y-664769D01*
X428993Y-664853D01*
G01X407326Y-641936D02*
Y-636936D01*
X408910D01*
X409416Y-637186D01*
X409733Y-637519D01*
X409860Y-638186D01*
X409733Y-638853D01*
X409353Y-639269D01*
X408910Y-639519D01*
X407326D01*
G01X408910D02*
X409860Y-641936D01*
G01X414960D02*
X412426D01*
Y-636936D01*
X414960D01*
G01X413946Y-639353D02*
X412426D01*
G01X417210Y-636936D02*
X418793Y-641936D01*
X420376Y-636936D01*
G01X423893Y-642103D02*
X423766Y-642019D01*
Y-641853D01*
X423893Y-641769D01*
X424020Y-641853D01*
Y-642019D01*
X423893Y-642103D01*
G01Y-639853D02*
X423766Y-639769D01*
Y-639603D01*
X423893Y-639519D01*
X424020Y-639603D01*
Y-639769D01*
X423893Y-639853D01*
G01X2010999Y-388000D02*
Y1475775D01*
X-407000D01*
Y-386798D01*
Y-755294D01*
Y-793716D01*
X-368578D01*
X1942346D01*
X2010999D01*
Y-725063D01*
Y-388000D01*
G01X-42602Y-671096D02*
X-41975Y-671621D01*
X-41270Y-671936D01*
X-40644D01*
X-40017Y-671621D01*
X-39547Y-671096D01*
X-39312Y-670361D01*
X-39469Y-669626D01*
X-39860Y-668996D01*
X-40565Y-668576D01*
X-41505Y-668366D01*
X-42054Y-667946D01*
X-42289Y-667211D01*
X-42132Y-666476D01*
X-41740Y-665951D01*
X-41192Y-665636D01*
X-40644D01*
X-40095Y-665846D01*
X-39625Y-666371D01*
G01X-36302Y-671936D02*
Y-665636D01*
G01X-33012D02*
Y-671936D01*
G01Y-668786D02*
X-36302D01*
G01X-29297Y-665636D02*
X-27417D01*
G01X-28357D02*
Y-671936D01*
G01X-29297D02*
X-27417D01*
G01X-20490D02*
X-23624D01*
Y-665636D01*
X-20490D01*
G01X-21744Y-668681D02*
X-23624D01*
G01X-17559Y-671936D02*
Y-665636D01*
X-13955Y-671936D01*
Y-665636D01*
G01X-9614Y-673091D02*
X-9300Y-671726D01*
G01X-3157Y-665636D02*
Y-671936D01*
G01X-4959Y-665636D02*
X-1355D01*
G01X1185Y-671936D02*
X3143Y-665636D01*
X5101Y-671936D01*
G01X4396Y-669731D02*
X1890D01*
G01X8503Y-665636D02*
X10383D01*
G01X9443D02*
Y-671936D01*
G01X8503D02*
X10383D01*
G01X13393Y-665636D02*
X14490Y-671936D01*
X15743Y-665636D01*
X16996Y-671936D01*
X18093Y-665636D01*
G01X20085Y-671936D02*
X22043Y-665636D01*
X24001Y-671936D01*
G01X23296Y-669731D02*
X20790D01*
G01X26541Y-671936D02*
Y-665636D01*
X30145Y-671936D01*
Y-665636D01*
G01X39376Y-671936D02*
Y-665636D01*
X41335D01*
X41961Y-665951D01*
X42353Y-666371D01*
X42510Y-667211D01*
X42353Y-668051D01*
X41883Y-668576D01*
X41335Y-668891D01*
X39376D01*
G01X41335D02*
X42510Y-671936D01*
G01X47243Y-672146D02*
X47086Y-672041D01*
Y-671831D01*
X47243Y-671726D01*
X47400Y-671831D01*
Y-672041D01*
X47243Y-672146D01*
G01X53543Y-671936D02*
X52916Y-671831D01*
X52368Y-671411D01*
X51898Y-670781D01*
X51585Y-670046D01*
X51428Y-669206D01*
Y-668366D01*
X51585Y-667526D01*
X51898Y-666791D01*
X52368Y-666161D01*
X52916Y-665741D01*
X53543Y-665636D01*
X54170Y-665741D01*
X54718Y-666161D01*
X55188Y-666791D01*
X55501Y-667526D01*
X55658Y-668366D01*
Y-669206D01*
X55501Y-670046D01*
X55188Y-670781D01*
X54718Y-671411D01*
X54170Y-671831D01*
X53543Y-671936D01*
G01X59843Y-672146D02*
X59686Y-672041D01*
Y-671831D01*
X59843Y-671726D01*
X60000Y-671831D01*
Y-672041D01*
X59843Y-672146D01*
G01X67866Y-666161D02*
X67396Y-665846D01*
X66848Y-665636D01*
X66221D01*
X65516Y-665951D01*
X64968Y-666476D01*
X64576Y-667106D01*
X64263Y-668156D01*
X64185Y-669101D01*
X64341Y-670046D01*
X64576Y-670676D01*
X65046Y-671306D01*
X65595Y-671726D01*
X66143Y-671936D01*
X66691D01*
X67240Y-671726D01*
X67710Y-671411D01*
X68101Y-670991D01*
G01X72443Y-672146D02*
X72286Y-672041D01*
Y-671831D01*
X72443Y-671726D01*
X72600Y-671831D01*
Y-672041D01*
X72443Y-672146D01*
G01X-42680Y-661936D02*
Y-655636D01*
G01X-39704D02*
X-42680Y-659521D01*
G01X-39234Y-661936D02*
X-41349Y-657736D01*
G01X-36380Y-655636D02*
Y-660151D01*
X-36067Y-661096D01*
X-35440Y-661726D01*
X-34657Y-661936D01*
X-33874Y-661726D01*
X-33247Y-661096D01*
X-32934Y-660151D01*
Y-655636D01*
G01X-26790Y-661936D02*
X-29924D01*
Y-655636D01*
X-26790D01*
G01X-28044Y-658681D02*
X-29924D01*
G01X-22997Y-655636D02*
X-21117D01*
G01X-22057D02*
Y-661936D01*
G01X-22997D02*
X-21117D01*
G01X-11102Y-661096D02*
X-10475Y-661621D01*
X-9770Y-661936D01*
X-9144D01*
X-8517Y-661621D01*
X-8047Y-661096D01*
X-7812Y-660361D01*
X-7969Y-659626D01*
X-8360Y-658996D01*
X-9065Y-658576D01*
X-10005Y-658366D01*
X-10554Y-657946D01*
X-10789Y-657211D01*
X-10632Y-656476D01*
X-10240Y-655951D01*
X-9692Y-655636D01*
X-9144D01*
X-8595Y-655846D01*
X-8125Y-656371D01*
G01X-4802Y-661936D02*
Y-655636D01*
G01X-1512D02*
Y-661936D01*
G01Y-658786D02*
X-4802D01*
G01X1185Y-661936D02*
X3143Y-655636D01*
X5101Y-661936D01*
G01X4396Y-659731D02*
X1890D01*
G01X7641Y-661936D02*
Y-655636D01*
X11245Y-661936D01*
Y-655636D01*
G01X20398Y-661936D02*
Y-655636D01*
G01X23688D02*
Y-661936D01*
G01Y-658786D02*
X20398D01*
G01X26698Y-661096D02*
X27325Y-661621D01*
X28030Y-661936D01*
X28656D01*
X29283Y-661621D01*
X29753Y-661096D01*
X29988Y-660361D01*
X29831Y-659626D01*
X29440Y-658996D01*
X28735Y-658576D01*
X27795Y-658366D01*
X27246Y-657946D01*
X27011Y-657211D01*
X27168Y-656476D01*
X27560Y-655951D01*
X28108Y-655636D01*
X28656D01*
X29205Y-655846D01*
X29675Y-656371D01*
G01X33703Y-655636D02*
X35583D01*
G01X34643D02*
Y-661936D01*
G01X33703D02*
X35583D01*
G01X38985D02*
X40943Y-655636D01*
X42901Y-661936D01*
G01X42196Y-659731D02*
X39690D01*
G01X45441Y-661936D02*
Y-655636D01*
X49045Y-661936D01*
Y-655636D01*
G01X54013Y-658786D02*
X55580D01*
Y-660676D01*
X55110Y-661306D01*
X54561Y-661726D01*
X53778Y-661936D01*
X52995Y-661726D01*
X52446Y-661306D01*
X51976Y-660676D01*
X51663Y-659941D01*
X51506Y-659101D01*
Y-658366D01*
X51663Y-657736D01*
X51976Y-657001D01*
X52446Y-656371D01*
X52916Y-655951D01*
X53543Y-655636D01*
X54091D01*
X54718Y-655846D01*
X55188Y-656266D01*
G01X59686Y-663091D02*
X60000Y-661726D01*
G01X66143Y-655636D02*
Y-661936D01*
G01X64341Y-655636D02*
X67945D01*
G01X70485Y-661936D02*
X72443Y-655636D01*
X74401Y-661936D01*
G01X73696Y-659731D02*
X71190D01*
G01X78743Y-661936D02*
X78116Y-661831D01*
X77568Y-661411D01*
X77098Y-660781D01*
X76785Y-660046D01*
X76628Y-659206D01*
Y-658366D01*
X76785Y-657526D01*
X77098Y-656791D01*
X77568Y-656161D01*
X78116Y-655741D01*
X78743Y-655636D01*
X79370Y-655741D01*
X79918Y-656161D01*
X80388Y-656791D01*
X80701Y-657526D01*
X80858Y-658366D01*
Y-659206D01*
X80701Y-660046D01*
X80388Y-660781D01*
X79918Y-661411D01*
X79370Y-661831D01*
X78743Y-661936D01*
G01X91343D02*
Y-659101D01*
X89776Y-655636D01*
G01X92910D02*
X91343Y-659101D01*
G01X95920Y-655636D02*
Y-660151D01*
X96233Y-661096D01*
X96860Y-661726D01*
X97643Y-661936D01*
X98426Y-661726D01*
X99053Y-661096D01*
X99366Y-660151D01*
Y-655636D01*
G01X101985Y-661936D02*
X103943Y-655636D01*
X105901Y-661936D01*
G01X105196Y-659731D02*
X102690D01*
G01X108441Y-661936D02*
Y-655636D01*
X112045Y-661936D01*
Y-655636D01*
G01X-42759Y-651936D02*
Y-645636D01*
X-39155Y-651936D01*
Y-645636D01*
G01X-34657Y-651936D02*
X-35284Y-651831D01*
X-35832Y-651411D01*
X-36302Y-650781D01*
X-36615Y-650046D01*
X-36772Y-649206D01*
Y-648366D01*
X-36615Y-647526D01*
X-36302Y-646791D01*
X-35832Y-646161D01*
X-35284Y-645741D01*
X-34657Y-645636D01*
X-34030Y-645741D01*
X-33482Y-646161D01*
X-33012Y-646791D01*
X-32699Y-647526D01*
X-32542Y-648366D01*
Y-649206D01*
X-32699Y-650046D01*
X-33012Y-650781D01*
X-33482Y-651411D01*
X-34030Y-651831D01*
X-34657Y-651936D01*
G01X-28357Y-652146D02*
X-28514Y-652041D01*
Y-651831D01*
X-28357Y-651726D01*
X-28200Y-651831D01*
Y-652041D01*
X-28357Y-652146D01*
G01X-22057Y-651936D02*
Y-645636D01*
X-22997Y-646896D01*
G01Y-651936D02*
X-21117D01*
G01X-15757D02*
X-15209Y-651831D01*
X-14582Y-651516D01*
X-14190Y-650991D01*
X-14034Y-650256D01*
X-14190Y-649521D01*
X-14660Y-648891D01*
X-15365Y-648576D01*
X-16149D01*
X-16619Y-648366D01*
X-17010Y-647841D01*
X-17167Y-647106D01*
X-16932Y-646371D01*
X-16384Y-645846D01*
X-15757Y-645636D01*
X-15130Y-645846D01*
X-14582Y-646371D01*
X-14347Y-647106D01*
X-14504Y-647841D01*
X-14895Y-648366D01*
X-15365Y-648576D01*
X-16149D01*
X-16854Y-648891D01*
X-17324Y-649521D01*
X-17480Y-650256D01*
X-17324Y-650991D01*
X-16932Y-651516D01*
X-16305Y-651831D01*
X-15757Y-651936D01*
G01X-9457D02*
X-8909Y-651831D01*
X-8282Y-651516D01*
X-7890Y-650991D01*
X-7734Y-650256D01*
X-7890Y-649521D01*
X-8360Y-648891D01*
X-9065Y-648576D01*
X-9849D01*
X-10319Y-648366D01*
X-10710Y-647841D01*
X-10867Y-647106D01*
X-10632Y-646371D01*
X-10084Y-645846D01*
X-9457Y-645636D01*
X-8830Y-645846D01*
X-8282Y-646371D01*
X-8047Y-647106D01*
X-8204Y-647841D01*
X-8595Y-648366D01*
X-9065Y-648576D01*
X-9849D01*
X-10554Y-648891D01*
X-11024Y-649521D01*
X-11180Y-650256D01*
X-11024Y-650991D01*
X-10632Y-651516D01*
X-10005Y-651831D01*
X-9457Y-651936D01*
G01X-3314Y-653091D02*
X-3000Y-651726D01*
G01X793Y-645636D02*
X1890Y-651936D01*
X3143Y-645636D01*
X4396Y-651936D01*
X5493Y-645636D01*
G01X11010Y-651936D02*
X7876D01*
Y-645636D01*
X11010D01*
G01X9756Y-648681D02*
X7876D01*
G01X13941Y-651936D02*
Y-645636D01*
X17545Y-651936D01*
Y-645636D01*
G01X26698Y-651936D02*
Y-645636D01*
G01X29988D02*
Y-651936D01*
G01Y-648786D02*
X26698D01*
G01X32293Y-645636D02*
X33390Y-651936D01*
X34643Y-645636D01*
X35896Y-651936D01*
X36993Y-645636D01*
G01X38985Y-651936D02*
X40943Y-645636D01*
X42901Y-651936D01*
G01X42196Y-649731D02*
X39690D01*
G01X52055Y-646686D02*
X52525Y-646056D01*
X53073Y-645741D01*
X53700Y-645636D01*
X54483Y-645846D01*
X55031Y-646371D01*
X55188Y-647001D01*
X55110Y-647631D01*
X54796Y-648156D01*
X53230Y-649206D01*
X52525Y-649941D01*
X52055Y-650991D01*
X51898Y-651936D01*
X55188D01*
G01X58041D02*
Y-645636D01*
X61645Y-651936D01*
Y-645636D01*
G01X64420Y-651936D02*
Y-645636D01*
X65986D01*
X66613Y-645951D01*
X67083Y-646371D01*
X67475Y-647001D01*
X67788Y-647736D01*
X67866Y-648786D01*
X67788Y-649836D01*
X67475Y-650571D01*
X67083Y-651201D01*
X66613Y-651621D01*
X65986Y-651936D01*
X64420D01*
G01X77176D02*
Y-645636D01*
X79135D01*
X79761Y-645951D01*
X80153Y-646371D01*
X80310Y-647211D01*
X80153Y-648051D01*
X79683Y-648576D01*
X79135Y-648891D01*
X77176D01*
G01X79135D02*
X80310Y-651936D01*
G01X83320D02*
Y-645636D01*
X84886D01*
X85513Y-645951D01*
X85983Y-646371D01*
X86375Y-647001D01*
X86688Y-647736D01*
X86766Y-648786D01*
X86688Y-649836D01*
X86375Y-650571D01*
X85983Y-651201D01*
X85513Y-651621D01*
X84886Y-651936D01*
X83320D01*
G01X91343Y-652146D02*
X91186Y-652041D01*
Y-651831D01*
X91343Y-651726D01*
X91500Y-651831D01*
Y-652041D01*
X91343Y-652146D01*
G01X-18657Y-639236D02*
X-21177Y-638819D01*
X-23382Y-637153D01*
X-25272Y-634653D01*
X-26532Y-631736D01*
X-27162Y-628403D01*
Y-625069D01*
X-26532Y-621736D01*
X-25272Y-618819D01*
X-23382Y-616320D01*
X-21177Y-614653D01*
X-18657Y-614236D01*
X-16137Y-614653D01*
X-13932Y-616320D01*
X-12042Y-618819D01*
X-10782Y-621736D01*
X-10152Y-625069D01*
Y-628403D01*
X-10782Y-631736D01*
X-12042Y-634653D01*
X-13932Y-637153D01*
X-16137Y-638819D01*
X-18657Y-639236D01*
G01X-16137Y-632569D02*
X-12357Y-639236D01*
G01X1188Y-622570D02*
Y-634236D01*
X2448Y-637153D01*
X4338Y-638819D01*
X6543Y-639236D01*
X8748Y-638819D01*
X10638Y-637153D01*
X11898Y-634236D01*
G01Y-639236D02*
Y-622570D01*
G01X37413Y-639236D02*
Y-622570D01*
G01Y-625486D02*
X36153Y-623820D01*
X34263Y-622986D01*
X32058Y-622570D01*
X29853Y-623403D01*
X27963Y-625069D01*
X26703Y-627570D01*
X26073Y-630903D01*
X26703Y-634236D01*
X27963Y-636737D01*
X29853Y-638403D01*
X32058Y-639236D01*
X34263Y-638819D01*
X36153Y-637570D01*
X37413Y-635903D01*
G01X51588Y-639236D02*
Y-622570D01*
G01Y-626736D02*
X52848Y-624653D01*
X54738Y-622986D01*
X57258Y-622570D01*
X59463Y-622986D01*
X61353Y-624653D01*
X62298Y-627570D01*
Y-639236D01*
G01X82143Y-614236D02*
Y-639236D01*
G01X77733Y-622570D02*
X86553D01*
G01X113013Y-639236D02*
Y-622570D01*
G01Y-625486D02*
X111753Y-623820D01*
X109863Y-622986D01*
X107658Y-622570D01*
X105453Y-623403D01*
X103563Y-625069D01*
X102303Y-627570D01*
X101673Y-630903D01*
X102303Y-634236D01*
X103563Y-636737D01*
X105453Y-638403D01*
X107658Y-639236D01*
X109863Y-638819D01*
X111753Y-637570D01*
X113013Y-635903D01*
G01X152693Y-618936D02*
Y-626936D01*
X156693D01*
G01X164493D02*
Y-621603D01*
G01Y-622536D02*
X164093Y-622003D01*
X163493Y-621736D01*
X162793Y-621603D01*
X162093Y-621869D01*
X161493Y-622403D01*
X161093Y-623203D01*
X160893Y-624269D01*
X161093Y-625336D01*
X161493Y-626136D01*
X162093Y-626669D01*
X162793Y-626936D01*
X163493Y-626803D01*
X164093Y-626403D01*
X164493Y-625870D01*
G01X168593Y-629336D02*
X169193Y-629603D01*
X169993Y-629336D01*
X170493Y-628803D01*
X170893Y-628136D01*
X171493Y-626003D01*
X172793Y-621603D01*
G01X169593D02*
X171493Y-626003D01*
G01X177193Y-623336D02*
X180393D01*
X180093Y-622403D01*
X179593Y-621869D01*
X178893Y-621603D01*
X178193Y-621736D01*
X177593Y-622136D01*
X177193Y-623069D01*
X176993Y-623870D01*
Y-624669D01*
X177193Y-625469D01*
X177693Y-626269D01*
X178293Y-626803D01*
X178993Y-626936D01*
X179693Y-626669D01*
X180393Y-625870D01*
G01X185293Y-626936D02*
Y-621603D01*
G01Y-622669D02*
X185793Y-622136D01*
X186293Y-621736D01*
X186993Y-621603D01*
X187493Y-621736D01*
X188093Y-622136D01*
G01X173993Y-676936D02*
Y-668936D01*
G01X177793D02*
X173993Y-673870D01*
G01X178393Y-676936D02*
X175693Y-671603D01*
G01X185993Y-676936D02*
Y-671603D01*
G01Y-672536D02*
X185593Y-672003D01*
X184993Y-671736D01*
X184293Y-671603D01*
X183593Y-671869D01*
X182993Y-672403D01*
X182593Y-673203D01*
X182393Y-674269D01*
X182593Y-675336D01*
X182993Y-676136D01*
X183593Y-676669D01*
X184293Y-676936D01*
X184993Y-676803D01*
X185593Y-676403D01*
X185993Y-675870D01*
G01X192193Y-671603D02*
Y-676936D01*
G01Y-669469D02*
X191993Y-669336D01*
Y-669069D01*
X192193Y-668936D01*
X192393Y-669069D01*
Y-669336D01*
X192193Y-669469D01*
G01X182493Y-643936D02*
X184893D01*
G01X183693D02*
Y-651936D01*
G01X182493D02*
X184893D01*
G01X189393D02*
Y-643936D01*
X193993Y-651936D01*
Y-643936D01*
G01X199693Y-651936D02*
Y-643936D01*
X198493Y-645536D01*
G01Y-651936D02*
X200893D01*
G01X203993Y-625336D02*
X204593Y-626269D01*
X205393Y-626803D01*
X206293Y-626936D01*
X207093Y-626803D01*
X207893Y-626136D01*
X208393Y-625336D01*
X208493Y-624536D01*
X208293Y-623603D01*
X207593Y-622936D01*
X206893Y-622669D01*
X205993D01*
G01X206893D02*
X207493Y-622269D01*
X207993Y-621603D01*
X208193Y-620803D01*
X207993Y-620003D01*
X207493Y-619336D01*
X206593Y-618936D01*
X205693Y-619069D01*
X204793Y-619603D01*
G01X279293Y-670269D02*
X279893Y-669469D01*
X280593Y-669069D01*
X281393Y-668936D01*
X282393Y-669203D01*
X283093Y-669869D01*
X283293Y-670669D01*
X283193Y-671470D01*
X282793Y-672136D01*
X280793Y-673469D01*
X279893Y-674403D01*
X279293Y-675736D01*
X279093Y-676936D01*
X283293D01*
G01X289193Y-668936D02*
X288393Y-669203D01*
X287793Y-669869D01*
X287393Y-670669D01*
X287093Y-671736D01*
X286993Y-672936D01*
X287093Y-674136D01*
X287393Y-675203D01*
X287793Y-676003D01*
X288393Y-676669D01*
X289193Y-676936D01*
X289993Y-676669D01*
X290593Y-676003D01*
X290993Y-675203D01*
X291293Y-674136D01*
X291393Y-672936D01*
X291293Y-671736D01*
X290993Y-670669D01*
X290593Y-669869D01*
X289993Y-669203D01*
X289193Y-668936D01*
G01X295293Y-670269D02*
X295893Y-669469D01*
X296593Y-669069D01*
X297393Y-668936D01*
X298393Y-669203D01*
X299093Y-669869D01*
X299293Y-670669D01*
X299193Y-671470D01*
X298793Y-672136D01*
X296793Y-673469D01*
X295893Y-674403D01*
X295293Y-675736D01*
X295093Y-676936D01*
X299293D01*
G01X303293Y-670269D02*
X303893Y-669469D01*
X304593Y-669069D01*
X305393Y-668936D01*
X306393Y-669203D01*
X307093Y-669869D01*
X307293Y-670669D01*
X307193Y-671470D01*
X306793Y-672136D01*
X304793Y-673469D01*
X303893Y-674403D01*
X303293Y-675736D01*
X303093Y-676936D01*
X307293D01*
G01X311393Y-677203D02*
X314993Y-668936D01*
G01X321193Y-676936D02*
Y-668936D01*
X319993Y-670536D01*
G01Y-676936D02*
X322393D01*
G01X327293Y-670269D02*
X327893Y-669469D01*
X328593Y-669069D01*
X329393Y-668936D01*
X330393Y-669203D01*
X331093Y-669869D01*
X331293Y-670669D01*
X331193Y-671470D01*
X330793Y-672136D01*
X328793Y-673469D01*
X327893Y-674403D01*
X327293Y-675736D01*
X327093Y-676936D01*
X331293D01*
G01X335393Y-677203D02*
X338993Y-668936D01*
G01X345193D02*
X344393Y-669203D01*
X343793Y-669869D01*
X343393Y-670669D01*
X343093Y-671736D01*
X342993Y-672936D01*
X343093Y-674136D01*
X343393Y-675203D01*
X343793Y-676003D01*
X344393Y-676669D01*
X345193Y-676936D01*
X345993Y-676669D01*
X346593Y-676003D01*
X346993Y-675203D01*
X347293Y-674136D01*
X347393Y-672936D01*
X347293Y-671736D01*
X346993Y-670669D01*
X346593Y-669869D01*
X345993Y-669203D01*
X345193Y-668936D01*
G01X351493Y-676003D02*
X352193Y-676669D01*
X352993Y-676936D01*
X353793Y-676669D01*
X354493Y-675870D01*
X354993Y-674669D01*
X355193Y-673469D01*
Y-672003D01*
X354993Y-670803D01*
X354493Y-669736D01*
X353893Y-669203D01*
X353193Y-668936D01*
X352393Y-669203D01*
X351793Y-669736D01*
X351393Y-670536D01*
X351193Y-671603D01*
X351393Y-672536D01*
X351893Y-673469D01*
X352493Y-674003D01*
X353193Y-674136D01*
X353993Y-673870D01*
X354593Y-673203D01*
X355193Y-672003D01*
G01X278993Y-651936D02*
Y-643936D01*
X280993D01*
X281793Y-644336D01*
X282393Y-644869D01*
X282893Y-645669D01*
X283293Y-646603D01*
X283393Y-647936D01*
X283293Y-649269D01*
X282893Y-650203D01*
X282393Y-651003D01*
X281793Y-651536D01*
X280993Y-651936D01*
X278993D01*
G01X286693D02*
X289193Y-643936D01*
X291693Y-651936D01*
G01X290793Y-649136D02*
X287593D01*
G01X297193Y-643936D02*
X296393Y-644203D01*
X295793Y-644869D01*
X295393Y-645669D01*
X295093Y-646736D01*
X294993Y-647936D01*
X295093Y-649136D01*
X295393Y-650203D01*
X295793Y-651003D01*
X296393Y-651669D01*
X297193Y-651936D01*
X297993Y-651669D01*
X298593Y-651003D01*
X298993Y-650203D01*
X299293Y-649136D01*
X299393Y-647936D01*
X299293Y-646736D01*
X298993Y-645669D01*
X298593Y-644869D01*
X297993Y-644203D01*
X297193Y-643936D01*
G01X303293Y-651936D02*
Y-643936D01*
X307093D01*
G01X305693Y-647803D02*
X303293D01*
G01X313193Y-643936D02*
X312393Y-644203D01*
X311793Y-644869D01*
X311393Y-645669D01*
X311093Y-646736D01*
X310993Y-647936D01*
X311093Y-649136D01*
X311393Y-650203D01*
X311793Y-651003D01*
X312393Y-651669D01*
X313193Y-651936D01*
X313993Y-651669D01*
X314593Y-651003D01*
X314993Y-650203D01*
X315293Y-649136D01*
X315393Y-647936D01*
X315293Y-646736D01*
X314993Y-645669D01*
X314593Y-644869D01*
X313993Y-644203D01*
X313193Y-643936D01*
G01X321193D02*
Y-651936D01*
G01X318893Y-643936D02*
X323493D01*
G01X326593Y-651936D02*
Y-643936D01*
X329193Y-650603D01*
X331793Y-643936D01*
Y-651936D01*
G01X334993D02*
Y-643936D01*
X336993D01*
X337793Y-644336D01*
X338393Y-644869D01*
X338893Y-645669D01*
X339293Y-646603D01*
X339393Y-647936D01*
X339293Y-649269D01*
X338893Y-650203D01*
X338393Y-651003D01*
X337793Y-651536D01*
X336993Y-651936D01*
X334993D01*
G01X347393Y-644603D02*
X346793Y-644203D01*
X346093Y-643936D01*
X345293D01*
X344393Y-644336D01*
X343693Y-645003D01*
X343193Y-645803D01*
X342793Y-647136D01*
X342693Y-648336D01*
X342893Y-649536D01*
X343193Y-650336D01*
X343793Y-651136D01*
X344493Y-651669D01*
X345193Y-651936D01*
X345893D01*
X346593Y-651669D01*
X347193Y-651269D01*
X347693Y-650736D01*
G01X350993Y-651936D02*
Y-643936D01*
X352993D01*
X353793Y-644336D01*
X354393Y-644869D01*
X354893Y-645669D01*
X355293Y-646603D01*
X355393Y-647936D01*
X355293Y-649269D01*
X354893Y-650203D01*
X354393Y-651003D01*
X353793Y-651536D01*
X352993Y-651936D01*
X350993D01*
G01X361193Y-643936D02*
X360393Y-644203D01*
X359793Y-644869D01*
X359393Y-645669D01*
X359093Y-646736D01*
X358993Y-647936D01*
X359093Y-649136D01*
X359393Y-650203D01*
X359793Y-651003D01*
X360393Y-651669D01*
X361193Y-651936D01*
X361993Y-651669D01*
X362593Y-651003D01*
X362993Y-650203D01*
X363293Y-649136D01*
X363393Y-647936D01*
X363293Y-646736D01*
X362993Y-645669D01*
X362593Y-644869D01*
X361993Y-644203D01*
X361193Y-643936D01*
G01X298418Y-624819D02*
Y-618519D01*
X301394D01*
G01X300298Y-621564D02*
X298418D01*
G01X306206Y-618519D02*
X305579Y-618729D01*
X305109Y-619254D01*
X304796Y-619884D01*
X304561Y-620724D01*
X304483Y-621669D01*
X304561Y-622614D01*
X304796Y-623454D01*
X305109Y-624084D01*
X305579Y-624609D01*
X306206Y-624819D01*
X306833Y-624609D01*
X307303Y-624084D01*
X307616Y-623454D01*
X307851Y-622614D01*
X307929Y-621669D01*
X307851Y-620724D01*
X307616Y-619884D01*
X307303Y-619254D01*
X306833Y-618729D01*
X306206Y-618519D01*
G01X312506D02*
Y-624819D01*
G01X310704Y-618519D02*
X314308D01*
G01X316456Y-626919D02*
X321156D01*
G01X323069Y-624819D02*
Y-618519D01*
X325106Y-623769D01*
X327143Y-618519D01*
Y-624819D01*
G01X332816D02*
Y-620619D01*
G01Y-621354D02*
X332503Y-620934D01*
X332033Y-620724D01*
X331484Y-620619D01*
X330936Y-620829D01*
X330466Y-621249D01*
X330153Y-621879D01*
X329996Y-622719D01*
X330153Y-623559D01*
X330466Y-624189D01*
X330936Y-624609D01*
X331484Y-624819D01*
X332033Y-624714D01*
X332503Y-624399D01*
X332816Y-623979D01*
G01X336374Y-624819D02*
Y-620619D01*
G01Y-621669D02*
X336688Y-621144D01*
X337158Y-620724D01*
X337784Y-620619D01*
X338333Y-620724D01*
X338803Y-621144D01*
X339038Y-621879D01*
Y-624819D01*
G01X345416D02*
Y-620619D01*
G01Y-621354D02*
X345103Y-620934D01*
X344633Y-620724D01*
X344084Y-620619D01*
X343536Y-620829D01*
X343066Y-621249D01*
X342753Y-621879D01*
X342596Y-622719D01*
X342753Y-623559D01*
X343066Y-624189D01*
X343536Y-624609D01*
X344084Y-624819D01*
X344633Y-624714D01*
X345103Y-624399D01*
X345416Y-623979D01*
G01X349209Y-626394D02*
X349758Y-626814D01*
X350384Y-626919D01*
X350933Y-626814D01*
X351403Y-626289D01*
X351716Y-625554D01*
Y-620619D01*
G01Y-621459D02*
X351403Y-621039D01*
X350933Y-620724D01*
X350384Y-620619D01*
X349758Y-620829D01*
X349366Y-621249D01*
X349053Y-621984D01*
X348896Y-622719D01*
X348974Y-623349D01*
X349288Y-624084D01*
X349758Y-624609D01*
X350384Y-624819D01*
X350854Y-624714D01*
X351403Y-624294D01*
X351716Y-623874D01*
G01X355431Y-621984D02*
X357938D01*
X357703Y-621249D01*
X357311Y-620829D01*
X356763Y-620619D01*
X356214Y-620724D01*
X355744Y-621039D01*
X355431Y-621774D01*
X355274Y-622404D01*
Y-623034D01*
X355431Y-623664D01*
X355823Y-624294D01*
X356293Y-624714D01*
X356841Y-624819D01*
X357389Y-624609D01*
X357938Y-623979D01*
G01X360556Y-624819D02*
Y-620619D01*
G01Y-621774D02*
X360791Y-621249D01*
X361183Y-620829D01*
X361731Y-620619D01*
X362279Y-620829D01*
X362671Y-621249D01*
X362906Y-621774D01*
Y-624819D01*
G01Y-621774D02*
X363141Y-621249D01*
X363533Y-620829D01*
X364081Y-620619D01*
X364629Y-620829D01*
X365021Y-621249D01*
X365256Y-621879D01*
Y-624819D01*
G01X368031Y-621984D02*
X370538D01*
X370303Y-621249D01*
X369911Y-620829D01*
X369363Y-620619D01*
X368814Y-620724D01*
X368344Y-621039D01*
X368031Y-621774D01*
X367874Y-622404D01*
Y-623034D01*
X368031Y-623664D01*
X368423Y-624294D01*
X368893Y-624714D01*
X369441Y-624819D01*
X369989Y-624609D01*
X370538Y-623979D01*
G01X374174Y-624819D02*
Y-620619D01*
G01Y-621669D02*
X374488Y-621144D01*
X374958Y-620724D01*
X375584Y-620619D01*
X376133Y-620724D01*
X376603Y-621144D01*
X376838Y-621879D01*
Y-624819D01*
G01X381806Y-618519D02*
Y-624819D01*
G01X380709Y-620619D02*
X382903D01*
G01X385756Y-626919D02*
X390456D01*
G01X395033Y-621459D02*
X395346Y-621144D01*
X395581Y-620619D01*
X395738Y-619884D01*
X395581Y-619254D01*
X395268Y-618834D01*
X394719Y-618519D01*
X392604D01*
Y-624819D01*
X395189D01*
X395738Y-624399D01*
X396051Y-623769D01*
X396208Y-623034D01*
X396051Y-622299D01*
X395581Y-621669D01*
X395033Y-621459D01*
X392604D01*
G01X398983Y-624819D02*
Y-618519D01*
X400549D01*
X401176Y-618834D01*
X401646Y-619254D01*
X402038Y-619884D01*
X402351Y-620619D01*
X402429Y-621669D01*
X402351Y-622719D01*
X402038Y-623454D01*
X401646Y-624084D01*
X401176Y-624504D01*
X400549Y-624819D01*
X398983D01*
G01X367693Y-679936D02*
Y-671936D01*
X366493Y-673536D01*
G01Y-679936D02*
X368893D01*
G01X373793Y-676603D02*
X374493Y-675669D01*
X375093Y-675136D01*
X375893Y-674869D01*
X376593Y-675136D01*
X377093Y-675669D01*
X377493Y-676469D01*
X377593Y-677403D01*
X377493Y-678203D01*
X377093Y-679003D01*
X376493Y-679669D01*
X375793Y-679936D01*
X374993Y-679669D01*
X374293Y-678870D01*
X373893Y-677669D01*
X373793Y-676336D01*
X373993Y-674603D01*
X374293Y-673669D01*
X374793Y-672736D01*
X375493Y-672069D01*
X376193Y-671936D01*
X376893Y-672203D01*
X377393Y-672869D01*
G01X383693Y-680203D02*
X383493Y-680069D01*
Y-679803D01*
X383693Y-679669D01*
X383893Y-679803D01*
Y-680069D01*
X383693Y-680203D01*
G01X389793Y-676603D02*
X390493Y-675669D01*
X391093Y-675136D01*
X391893Y-674869D01*
X392593Y-675136D01*
X393093Y-675669D01*
X393493Y-676469D01*
X393593Y-677403D01*
X393493Y-678203D01*
X393093Y-679003D01*
X392493Y-679669D01*
X391793Y-679936D01*
X390993Y-679669D01*
X390293Y-678870D01*
X389893Y-677669D01*
X389793Y-676336D01*
X389993Y-674603D01*
X390293Y-673669D01*
X390793Y-672736D01*
X391493Y-672069D01*
X392193Y-671936D01*
X392893Y-672203D01*
X393393Y-672869D01*
G01X412693Y-679936D02*
Y-671936D01*
X411493Y-673536D01*
G01Y-679936D02*
X413893D01*
G01X420493D02*
X420693Y-678203D01*
X420993Y-676736D01*
X421393Y-675403D01*
X421893Y-673936D01*
X422693Y-671936D01*
X418693D01*
G01X428693Y-680203D02*
X428493Y-680069D01*
Y-679803D01*
X428693Y-679669D01*
X428893Y-679803D01*
Y-680069D01*
X428693Y-680203D01*
G01X434793Y-673269D02*
X435393Y-672469D01*
X436093Y-672069D01*
X436893Y-671936D01*
X437893Y-672203D01*
X438593Y-672869D01*
X438793Y-673669D01*
X438693Y-674470D01*
X438293Y-675136D01*
X436293Y-676469D01*
X435393Y-677403D01*
X434793Y-678736D01*
X434593Y-679936D01*
X438793D01*
G01X432493Y-654936D02*
Y-646936D01*
X434493D01*
X435293Y-647336D01*
X435893Y-647869D01*
X436393Y-648669D01*
X436793Y-649603D01*
X436893Y-650936D01*
X436793Y-652269D01*
X436393Y-653203D01*
X435893Y-654003D01*
X435293Y-654536D01*
X434493Y-654936D01*
X432493D01*
G54D18*
G01X-61000Y382816D02*
Y367956D01*
X-60500Y367456D01*
X-49687D01*
X-48667Y366436D01*
Y364836D01*
X-49687Y363816D01*
X-63434D01*
X-66527Y360723D01*
Y356189D01*
X-63434Y353096D01*
X-49687D01*
X-48667Y352076D01*
Y350476D01*
X-49687Y349456D01*
X-63434D01*
X-66527Y346363D01*
Y341829D01*
X-63434Y338736D01*
X-49687D01*
X-48667Y337716D01*
Y336116D01*
X-49687Y335096D01*
X-63434D01*
X-66527Y332003D01*
Y327469D01*
X-63434Y324376D01*
X-49687D01*
X-48667Y323356D01*
Y321756D01*
X-49687Y320736D01*
X-63434D01*
X-66527Y317643D01*
Y313109D01*
X-63434Y310016D01*
X-49687D01*
X-48667Y308996D01*
Y307396D01*
X-49687Y306376D01*
X-63434D01*
X-66527Y303283D01*
Y298749D01*
X-63434Y295656D01*
X-49687D01*
X-48667Y294636D01*
Y293036D01*
X-49687Y292016D01*
X-63434D01*
X-66527Y288923D01*
Y284389D01*
X-63434Y281296D01*
X-49687D01*
X-48667Y280276D01*
Y277920D01*
X-47647Y276900D01*
X-46147D01*
X-45127Y277920D01*
Y281743D01*
X-48220Y284836D01*
X-61967D01*
X-62987Y285856D01*
Y287456D01*
X-61967Y288476D01*
X-48220D01*
X-45127Y291569D01*
Y296103D01*
X-48220Y299196D01*
X-61967D01*
X-62987Y300216D01*
Y301816D01*
X-61967Y302836D01*
X-48220D01*
X-45127Y305929D01*
Y310463D01*
X-48220Y313556D01*
X-61967D01*
X-62987Y314576D01*
Y316176D01*
X-61967Y317196D01*
X-48220D01*
X-45127Y320289D01*
Y324823D01*
X-48220Y327916D01*
X-61967D01*
X-62987Y328936D01*
Y330536D01*
X-61967Y331556D01*
X-48220D01*
X-45127Y334649D01*
Y339183D01*
X-48220Y342276D01*
X-61967D01*
X-62987Y343296D01*
Y344896D01*
X-61967Y345916D01*
X-48220D01*
X-45127Y349009D01*
Y353543D01*
X-48220Y356636D01*
X-61967D01*
X-62987Y357656D01*
Y359256D01*
X-61967Y360276D01*
X-48220D01*
X-45127Y363369D01*
Y367903D01*
X-48220Y370996D01*
X-50500D01*
X-51000Y371496D01*
Y382816D01*
G01X26300Y374400D02*
X20500D01*
X17500Y371400D01*
Y344400D01*
X18700Y343200D01*
X25900D01*
X27800Y341300D01*
Y337200D01*
X26044Y335444D01*
X24544D01*
X21770Y332670D01*
Y317554D01*
X10893Y306677D01*
Y122884D01*
X25307Y108470D01*
X27545D01*
X27546Y108471D01*
X35498D01*
X42970Y100999D01*
Y90000D01*
X44970Y88000D01*
X59000D01*
X69280Y77720D01*
X96918D01*
X97299Y78101D01*
X106681D01*
X109657Y75125D01*
X111670D01*
X115136Y78591D01*
X121910D01*
X128001Y72500D01*
X131870D01*
X134275Y74905D01*
X148498D01*
X155460Y81867D01*
X176587D01*
X179900Y85180D01*
Y91300D01*
G01X240000Y67400D02*
Y72203D01*
X232955Y79248D01*
X163188D01*
X159966Y76026D01*
Y74034D01*
X156767Y70835D01*
X148320D01*
X143845Y66360D01*
X125496D01*
X119747Y72109D01*
X114807D01*
X114287Y72629D01*
X108673D01*
X105661Y75641D01*
X102581D01*
X98640Y71700D01*
X78965D01*
X78265Y72400D01*
X67500D01*
X55400Y84500D01*
X44010D01*
X40510Y88000D01*
Y95631D01*
X30130Y106011D01*
X28566D01*
X28565Y106010D01*
X24287D01*
X8433Y121864D01*
Y307698D01*
X19310Y318575D01*
Y334919D01*
X17662Y338899D01*
X10700Y345861D01*
Y413340D01*
X14190Y416830D01*
X36473D01*
X42503Y410800D01*
X60102D01*
X60900Y410002D01*
Y407501D01*
X64731Y403670D01*
X68100D01*
X71170Y400600D01*
X82605D01*
X82905Y400300D01*
X91766D01*
X94066Y398000D01*
X111500D01*
X117943Y391557D01*
X120063D01*
X121000Y390620D01*
Y390100D01*
X121947Y389153D01*
X123962Y388318D01*
X128379D01*
X130922Y385775D01*
X146152D01*
X149727Y389350D01*
X152500D01*
X154500Y387350D01*
G01X149000Y383070D02*
X148315Y382385D01*
X129515D01*
X127435Y384465D01*
X123665D01*
X122400Y383200D01*
X119601D01*
X111641Y391160D01*
X93640D01*
X92124Y392676D01*
X76457D01*
X71803Y397330D01*
X64769D01*
X57409Y404690D01*
X41656D01*
X39646Y406700D01*
X36002D01*
X27102Y415600D01*
X14700D01*
X12000Y412900D01*
Y346400D01*
X18693Y339707D01*
X20540Y335247D01*
Y318064D01*
X9663Y307187D01*
Y122374D01*
X24797Y107240D01*
X28055D01*
X28056Y107241D01*
X30640D01*
X41740Y96141D01*
Y89000D01*
X44240Y86500D01*
X58646D01*
X71516Y73630D01*
X78775D01*
X79305Y73100D01*
X98300D01*
X102071Y76871D01*
X106171D01*
X109148Y73894D01*
X112345D01*
X115777Y77326D01*
X120559D01*
X126885Y71000D01*
X134400D01*
X135000Y70400D01*
X145900D01*
X147800Y72300D01*
X151998D01*
X155998Y76300D01*
X158500D01*
X162837Y80637D01*
X221757D01*
X224330Y83210D01*
G01X14000Y401700D02*
X15570Y403270D01*
X37360D01*
X40550Y400080D01*
Y397245D01*
X41795Y396000D01*
X60201D01*
X61791Y394410D01*
X65294D01*
X70683Y389021D01*
X83246D01*
X84700Y387567D01*
Y382800D01*
X87200Y380300D01*
X89000D01*
X90766Y378534D01*
Y377883D01*
G01X87617Y390481D02*
X71289D01*
X65900Y395870D01*
X62397D01*
X60407Y397860D01*
X53410D01*
X47810Y403460D01*
X39802D01*
X38132Y405130D01*
X15570D01*
X14000Y406700D01*
G01X87617Y387332D02*
X85968D01*
X83549Y389751D01*
X70986D01*
X65597Y395140D01*
X62094D01*
X60304Y396930D01*
X52610D01*
X49925Y399615D01*
X42331D01*
X37746Y404200D01*
X14000D01*
G01X160700Y445550D02*
X148850D01*
X143630Y440330D01*
X114880D01*
X114110Y441100D01*
X68640D01*
X67340Y439800D01*
X54001D01*
X47901Y433700D01*
X40999D01*
X38199Y436500D01*
X21200D01*
X14700Y430000D01*
Y425000D01*
G01X106574Y280028D02*
X102106Y275560D01*
X89416D01*
X88241Y274385D01*
X84201D01*
X77441Y267625D01*
X59475D01*
X55835Y271265D01*
Y298457D01*
X48072Y306220D01*
X46480D01*
X45610Y307090D01*
Y310290D01*
X45599Y310301D01*
Y310700D01*
X39439Y316860D01*
X39040D01*
X39030Y316870D01*
X37931D01*
X34336Y320465D01*
X32637D01*
X28400Y324699D01*
Y329498D01*
X33902Y335000D01*
X35500D01*
G01X37020Y385600D02*
X32991D01*
X29100Y381709D01*
Y374100D01*
X27900Y372900D01*
Y342900D01*
X28730Y342070D01*
Y334330D01*
X27470Y333070D01*
Y321628D01*
X32158Y316940D01*
X32201Y316905D01*
X32257Y316899D01*
X35344D01*
X36314Y315929D01*
X38970D01*
X44669Y310230D01*
Y301240D01*
X46708Y299201D01*
X53198D01*
X54905Y297494D01*
Y270795D01*
X59005Y266695D01*
X77827D01*
X84587Y273455D01*
X88627D01*
X89802Y274630D01*
X103673D01*
X108339Y279296D01*
Y280760D01*
X107900Y281199D01*
Y286468D01*
X109636Y288204D01*
X121155D01*
X123295Y290344D01*
Y293672D01*
X124865Y295242D01*
Y298845D01*
X129060Y303040D01*
X146873D01*
X149561Y300352D01*
X157132D01*
X159235Y298249D01*
X164822D01*
X167511Y295560D01*
X175099D01*
X177788Y298249D01*
X180407D01*
X182232Y296424D01*
G01X31300Y329900D02*
X30100Y328700D01*
Y325703D01*
X33903Y321900D01*
X34500D01*
X38580Y317820D01*
X40280D01*
X42900Y315200D01*
X47100D01*
X56446Y305854D01*
X56880Y304806D01*
Y280720D01*
X69045Y268555D01*
X77055D01*
X83815Y275315D01*
X87855D01*
X89380Y276840D01*
X95640D01*
X108957Y290157D01*
X117286D01*
X120600Y293471D01*
G01X31600Y379600D02*
Y373601D01*
X30000Y372001D01*
Y351522D01*
X39770Y341752D01*
Y339958D01*
X40636Y337867D01*
X51830Y330388D01*
X58320Y327700D01*
X65900D01*
X68500Y325100D01*
G01X85500Y326700D02*
X83500Y328700D01*
X79822D01*
X77717Y330805D01*
X70058D01*
X69063Y331800D01*
X55494D01*
X53620Y332576D01*
X42834Y339785D01*
X42455Y340494D01*
Y342547D01*
X32890Y352112D01*
Y362512D01*
X33403Y363025D01*
X35900D01*
G01X95060Y327625D02*
X93965D01*
X86200Y319860D01*
X80341D01*
X79200Y321001D01*
Y325842D01*
X76697Y328345D01*
X69038D01*
X68283Y329100D01*
X58438D01*
X52341Y331626D01*
X41924Y338587D01*
X41000Y340315D01*
Y342262D01*
X31300Y351962D01*
Y371501D01*
X32999Y373200D01*
X38300D01*
X39800Y374700D01*
Y392774D01*
X37659Y394915D01*
X36911D01*
G01X32700Y395381D02*
Y400300D01*
X33500Y401100D01*
X37789D01*
X39320Y399569D01*
Y396734D01*
X42700Y393354D01*
Y390100D01*
X43235Y389565D01*
X47035D01*
X49500Y387100D01*
Y371700D01*
X57562Y363638D01*
X66214D01*
X67292Y362560D01*
Y361566D01*
X68370Y360488D01*
X86152D01*
X87617Y359023D01*
G01X25202Y425329D02*
X26036Y424495D01*
X34695D01*
X35765Y425565D01*
X46535D01*
X54770Y417330D01*
X69452D01*
X72927Y420805D01*
X96132D01*
X98840Y423513D01*
Y425960D01*
X102490Y429610D01*
X112118D01*
X117475Y424253D01*
Y419463D01*
X120258Y416680D01*
X126220D01*
X129082Y413818D01*
X132659D01*
X133058Y413419D01*
X133059D01*
X133143Y413335D01*
X136865D01*
X137900Y412300D01*
X140600D01*
G01X29400Y430900D02*
X32200D01*
X36305Y426795D01*
X47045D01*
X52742Y421098D01*
X60301D01*
X67603Y428400D01*
X91500D01*
X93259Y426641D01*
Y424200D01*
G01X23677Y422419D02*
X23001Y423095D01*
Y433001D01*
X24800Y434800D01*
X37200D01*
X39700Y432300D01*
X48400D01*
X53700Y437600D01*
X68100D01*
X70300Y439800D01*
X77000D01*
X80875Y435925D01*
X97025D01*
X100700Y439600D01*
X113300D01*
X115300Y437600D01*
X143000D01*
X145300Y439900D01*
X159000D01*
X161400Y442300D01*
X169700D01*
X173300Y438700D01*
X185400D01*
X189105Y442405D01*
X206295D01*
X208600Y440100D01*
X231500D01*
X233200Y438400D01*
X243800D01*
X249900Y432300D01*
X255100D01*
X259400Y428000D01*
X265800D01*
X271600Y433800D01*
X274400D01*
X276390Y431810D01*
X276400D01*
G01X77600Y431400D02*
X76000Y429800D01*
X70099D01*
X68062Y431837D01*
Y433734D01*
X66026Y435770D01*
X53671D01*
X48901Y431000D01*
X33900D01*
X32100Y432800D01*
G01X187400Y101500D02*
X184600Y104300D01*
X168900D01*
X165330Y100730D01*
X160134D01*
X155500Y96096D01*
Y88110D01*
X149485Y82095D01*
X142882Y79360D01*
X138540D01*
X132900Y85000D01*
X125540D01*
X124795Y85745D01*
X120861D01*
X119381Y84265D01*
X102147D01*
X96532Y78650D01*
X69850D01*
X59000Y89500D01*
X48500D01*
X45500Y92500D01*
G01X123120Y213088D02*
X123119Y213089D01*
Y217887D01*
X115769Y225237D01*
X112498Y227423D01*
X108618Y229030D01*
X101165D01*
X96428Y227068D01*
X94060Y224700D01*
X90100D01*
X77167Y211767D01*
X65167D01*
X57400Y204000D01*
X51100D01*
X50000Y202900D01*
X47800D01*
X44719Y205981D01*
Y221319D01*
X47815Y228794D01*
Y250013D01*
X62402Y264600D01*
X77400D01*
X81465Y268665D01*
X84232D01*
X85265Y267632D01*
Y266875D01*
X87230Y264910D01*
X91908D01*
X99768Y272770D01*
X104445D01*
X110370Y278695D01*
Y282733D01*
X109835Y283268D01*
Y284732D01*
X111303Y286200D01*
X137804D01*
X148014Y275990D01*
X161388D01*
X172078Y286680D01*
X198595D01*
X207615Y295700D01*
X216877D01*
X221182Y300005D01*
X238003D01*
X242700Y304702D01*
Y306800D01*
G01X47948Y201000D02*
X49840D01*
X51440Y202600D01*
X58000D01*
X65937Y210537D01*
X81637D01*
X97123Y226023D01*
X101413Y227800D01*
X108113D01*
X112199Y226107D01*
X114891Y224309D01*
X120030Y219170D01*
Y205570D01*
X120858Y204742D01*
X124338D01*
G01X184645Y178646D02*
X183180Y177181D01*
X179819D01*
X173200Y183800D01*
X159900D01*
X153900Y189800D01*
X152200D01*
X149329Y186929D01*
X125116D01*
X122480Y184293D01*
Y176332D01*
X112668Y166520D01*
X100010D01*
X89618Y176912D01*
Y193732D01*
X84215Y199135D01*
X70744D01*
X67059Y202820D01*
X63110D01*
X62220Y201930D01*
Y199722D01*
X60633Y198135D01*
X47865D01*
X39900Y206100D01*
Y211000D01*
G01X112900Y239200D02*
X105212Y242384D01*
X88084D01*
X84130Y238430D01*
X76010D01*
X75510Y238930D01*
X66510D01*
X64810Y240630D01*
X62493D01*
X50678Y235736D01*
X49045Y234103D01*
Y228284D01*
X45949Y220809D01*
Y210851D01*
X50300Y206500D01*
X56798D01*
X68511Y218213D01*
X70453Y222900D01*
G01X78600Y283970D02*
Y284098D01*
X77288Y285410D01*
X75043Y286340D01*
X68220D01*
X59600Y294960D01*
Y304708D01*
X56425Y312375D01*
Y312392D01*
X55392Y313425D01*
X55375D01*
X54200Y314600D01*
X49440D01*
X47610Y316430D01*
X46667D01*
X43760Y319337D01*
X38863D01*
X34300Y323900D01*
Y328299D01*
X38000Y331999D01*
Y338000D01*
X35500Y340500D01*
G01X39100Y321600D02*
X44180D01*
X49780Y316000D01*
X54600D01*
X57625Y312975D01*
X61000Y304820D01*
Y295301D01*
X68731Y287570D01*
X75288D01*
X77912Y286483D01*
X82564D01*
X87281Y291200D01*
X91500D01*
X95510Y295210D01*
Y296259D01*
X108551Y309300D01*
X125100D01*
X126360Y310560D01*
X137642D01*
X140782Y313700D01*
X145399D01*
X147959Y311140D01*
X154536D01*
X156436Y313040D01*
X158710D01*
X160995Y315325D01*
X163975D01*
X164500Y314800D01*
G01X44220Y341008D02*
X45212Y342000D01*
X46700D01*
X55600Y333100D01*
X69503D01*
X70568Y332035D01*
X78227D01*
X79962Y330300D01*
X85800D01*
X89100Y333600D01*
X95200D01*
X96261Y332539D01*
X98207D01*
X99617Y333123D01*
X102780Y336286D01*
X103180D01*
G01X188546Y326356D02*
X186386Y324196D01*
X181449D01*
X179120Y326525D01*
X170111D01*
X167936Y328700D01*
X135300D01*
X130900Y333100D01*
X123440D01*
X122530Y334010D01*
Y337270D01*
X119990Y339810D01*
X117544D01*
X117254Y340100D01*
X104351D01*
X100505Y336254D01*
Y335845D01*
X98760Y334100D01*
X97961Y333769D01*
X96831D01*
X95600Y335000D01*
X88701D01*
X85301Y331600D01*
X80403D01*
X78433Y333570D01*
X75530D01*
X72760Y336340D01*
X69680D01*
X68120Y337900D01*
X54000D01*
X47900Y344000D01*
X44500D01*
G01X78700Y340000D02*
X74100D01*
X72900Y338800D01*
X70700D01*
X69000Y340500D01*
X55420D01*
X46155Y349765D01*
X43435D01*
X40070Y353130D01*
Y368955D01*
X37800Y371225D01*
G01X44525Y384000D02*
X41030Y380505D01*
Y370530D01*
X41300Y370260D01*
Y355249D01*
X43149Y353400D01*
X45999D01*
X46169Y353230D01*
X46170D01*
X55700Y343700D01*
X58899D01*
X59999Y344800D01*
X82600D01*
X84024Y343376D01*
X96225D01*
X97401Y342200D01*
X97967D01*
X97997Y342170D01*
X108503D01*
X109033Y342700D01*
X118134D01*
X118564Y342270D01*
X131010D01*
X139240Y350500D01*
X148532D01*
X159102Y361070D01*
X171390D01*
X186500Y345960D01*
Y343560D01*
X188629Y341431D01*
X194531D01*
X194800Y341700D01*
G01X124350Y352450D02*
X122150D01*
X115235Y345535D01*
X108235D01*
X107403Y344703D01*
X99585D01*
X97373Y346915D01*
X86385D01*
X82200Y351100D01*
X57200D01*
X52300Y356000D01*
X50899D01*
X47520Y359379D01*
Y361005D01*
X44525Y364000D01*
G01X150900Y360325D02*
X150290Y360935D01*
X140535D01*
X135170Y355570D01*
Y350930D01*
X134365Y350125D01*
Y349358D01*
X133332Y348325D01*
X131868D01*
X129593Y350600D01*
X122040D01*
X116245Y344805D01*
X108538D01*
X107533Y343800D01*
X99099D01*
X96799Y346100D01*
X85100D01*
X83268Y347932D01*
X53208D01*
X46290Y354850D01*
Y356810D01*
X45100Y358000D01*
X43160D01*
X42600Y358560D01*
Y366075D01*
X44525Y368000D01*
G01X44500Y351600D02*
X46060D01*
X55860Y341800D01*
X69900D01*
X70800Y342700D01*
X78800D01*
X80900Y340600D01*
X82800D01*
X84846Y342646D01*
X95554D01*
X96800Y341400D01*
X117694D01*
X118054Y341040D01*
X131520D01*
X134425Y343945D01*
X143717D01*
X152572Y352800D01*
X172599D01*
X179625Y345774D01*
Y341487D01*
X181061Y340051D01*
X184278D01*
X188541Y335788D01*
X191589D01*
X193671Y337870D01*
X201151D01*
X204581Y341300D01*
X220438D01*
X221698Y340040D01*
X228230D01*
G01X37067Y398337D02*
X38020Y397384D01*
Y396630D01*
X38258Y396056D01*
X41470Y392844D01*
Y387330D01*
X43035Y385765D01*
X45835D01*
X46800Y384800D01*
Y379600D01*
X45400Y378200D01*
X43500D01*
X42260Y376960D01*
Y371040D01*
X43500Y369800D01*
X46000D01*
X48900Y366900D01*
Y360599D01*
X52099Y357400D01*
X58400D01*
X61611Y354189D01*
X88224D01*
X89082Y353331D01*
Y352218D01*
X90100Y351200D01*
X91300D01*
X92926Y349574D01*
X93916D01*
G01X200000Y407040D02*
X195290Y411750D01*
X188390D01*
X186875Y410235D01*
X152347D01*
X151314Y411268D01*
Y411283D01*
X150232Y412365D01*
X144962D01*
X142562Y409965D01*
X137635D01*
X135495Y412105D01*
X132632D01*
X132149Y412588D01*
X128572D01*
X125710Y415450D01*
X119748D01*
X116245Y418953D01*
Y423743D01*
X111608Y428380D01*
X103000D01*
X100070Y425450D01*
Y423003D01*
X96642Y419575D01*
X73522D01*
X70047Y416100D01*
X50300D01*
X43600Y422800D01*
G01X48050Y436350D02*
X51900Y440200D01*
X52661D01*
X53491Y441030D01*
X66830D01*
X68130Y442330D01*
X87279D01*
X92249Y447300D01*
X98500D01*
X100860Y449660D01*
X111430D01*
X118140Y442950D01*
X141550D01*
X153760Y455160D01*
X161100D01*
X174390Y441870D01*
X183709D01*
X190174Y448335D01*
X195586D01*
X198751Y451500D01*
X219103D01*
X222999Y447604D01*
X228718Y445235D01*
X233738D01*
X233748Y445225D01*
X236945D01*
X237504Y445784D01*
X241436D01*
G01X107000Y44500D02*
X104800Y46700D01*
X56200D01*
X53600Y44100D01*
G01X112800Y60400D02*
X109600Y57200D01*
X56600D01*
X51000Y51600D01*
Y40914D01*
X55704Y36210D01*
X56348D01*
G01X280910Y102880D02*
Y100530D01*
X276629Y96249D01*
X271659D01*
X269060Y93650D01*
Y91800D01*
X261960Y84700D01*
X251920D01*
X246480Y90140D01*
X234820D01*
X234235Y89555D01*
X204958D01*
X189283Y105230D01*
X168514D01*
X164944Y101660D01*
X159748D01*
X154570Y96482D01*
Y88496D01*
X149058Y82984D01*
X142554Y80290D01*
X138926D01*
X133286Y85930D01*
X125926D01*
X125181Y86675D01*
X120395D01*
X118915Y85195D01*
X101761D01*
X96146Y79580D01*
X70920D01*
X59630Y90870D01*
Y105976D01*
X62240Y112278D01*
Y119830D01*
X61440Y120630D01*
X59945D01*
G01X53400Y102788D02*
X58060Y107448D01*
Y187371D01*
X64389Y193700D01*
X80900D01*
X86828Y187772D01*
Y175753D01*
X98851Y163730D01*
X113827D01*
X122097Y172000D01*
X129100D01*
X134215Y177115D01*
X140184D01*
X143177Y174122D01*
X173421D01*
X175196Y172347D01*
G01X52948Y200700D02*
X58000D01*
X61350Y204050D01*
X70250D01*
X71565Y202735D01*
X83247D01*
X91478Y194504D01*
Y177686D01*
X100784Y168380D01*
X111896D01*
X120620Y177104D01*
Y185065D01*
X124344Y188789D01*
X141437D01*
X144034Y191386D01*
X149380Y193600D01*
X153400D01*
X158400Y188600D01*
X165500D01*
X167560Y186540D01*
X173060D01*
X176340Y183260D01*
X182160D01*
X183000Y184100D01*
Y185640D01*
X183900Y186540D01*
X186740D01*
X189900Y189700D01*
X192400D01*
X193400Y190700D01*
Y194243D01*
X195459Y196302D01*
Y211860D01*
X199425Y215826D01*
X205749D01*
X209842Y219919D01*
Y222703D01*
G01X122876Y245300D02*
X125770Y242406D01*
Y232489D01*
X128500Y229759D01*
Y224138D01*
X126592Y222230D01*
X121832D01*
X117078Y226984D01*
X113499Y229376D01*
X109119Y231190D01*
X100732D01*
X95205Y228901D01*
X93404Y227100D01*
X88867D01*
X86567Y224800D01*
X69400D01*
X58823Y214223D01*
Y213531D01*
G01X51600Y241200D02*
X53700Y243300D01*
X73081D01*
X76721Y239660D01*
X83620D01*
X87574Y243614D01*
X105457D01*
X110805Y241400D01*
X117040D01*
X117840Y242200D01*
G01X103580Y237400D02*
X101580Y239400D01*
X87000D01*
X84800Y237200D01*
X75500D01*
X75000Y237700D01*
X66000D01*
X64300Y239400D01*
X62738D01*
X52669Y235229D01*
X51010Y233570D01*
G01X149862Y243788D02*
Y242963D01*
X146908Y240009D01*
X137867D01*
X128321Y249555D01*
X121577D01*
X119682Y247660D01*
X116653D01*
X115088Y249225D01*
X112092D01*
X111101Y248234D01*
X99780D01*
X92419Y255595D01*
X85835D01*
X80765Y250525D01*
X65475D01*
X63300Y252700D01*
Y256100D01*
X61900Y257500D01*
X57800D01*
X50700Y250400D01*
G01X100700Y293600D02*
Y293000D01*
X85475Y277775D01*
X71586D01*
X71086Y277275D01*
X64027D01*
X59500Y281802D01*
Y281803D01*
X59435Y281868D01*
Y284435D01*
X61400Y286400D01*
Y291000D01*
X58370Y294030D01*
Y304461D01*
X57119Y307481D01*
X54660Y309940D01*
Y311660D01*
G01X108551Y294241D02*
Y291751D01*
X95500Y278700D01*
X89500D01*
X87345Y276545D01*
X72096D01*
X71481Y275930D01*
X63632D01*
X58205Y281357D01*
Y287380D01*
X58900Y288075D01*
G01X170561Y306631D02*
X166569D01*
X163705Y309495D01*
X157687D01*
X155362Y307170D01*
X127926D01*
X126666Y305910D01*
X109957D01*
X98900Y294853D01*
Y292516D01*
X85089Y278705D01*
X71200D01*
X70700Y278205D01*
X65595D01*
X61200Y282600D01*
G01X48420Y321616D02*
X50484D01*
X51700Y320400D01*
X53700D01*
X55700Y322400D01*
X59360D01*
X71600Y310160D01*
Y304900D01*
X70500Y303800D01*
Y292500D01*
X74200Y288800D01*
X75535D01*
X78159Y287713D01*
X82054D01*
X98701Y304360D01*
X100060D01*
X101860Y306160D01*
Y309870D01*
X100530Y311200D01*
X99990D01*
G01X124935Y324900D02*
X124535Y325300D01*
X113694D01*
X109510Y329484D01*
X105023D01*
X103990Y328451D01*
Y327791D01*
X101000Y324801D01*
Y322889D01*
X95511Y317400D01*
X79101D01*
X77801Y318700D01*
X64800D01*
X57300Y326200D01*
X53820D01*
X52820Y325200D01*
G01X65607Y359023D02*
X57452D01*
X52475Y364000D01*
G01X125650Y368650D02*
X118550D01*
X114080Y373120D01*
X109380D01*
X104060Y367800D01*
X68900D01*
X68300Y368400D01*
X56623D01*
X55294Y369729D01*
G01X58620Y408779D02*
Y405580D01*
X66140Y398060D01*
X72106D01*
X76760Y393406D01*
X85107D01*
X88300Y396599D01*
Y398100D01*
X89600Y399400D01*
X91300D01*
X93700Y397000D01*
X110900D01*
X118200Y389700D01*
X119200D01*
G01X63200Y408600D02*
X63000Y408400D01*
Y407360D01*
X65460Y404900D01*
X68610D01*
X72029Y401481D01*
X83464D01*
X83765Y401180D01*
X91920D01*
X94100Y399000D01*
X112101D01*
X116001Y395100D01*
X122100D01*
X122600Y394600D01*
G01X102999Y131799D02*
X99723Y135075D01*
X96026D01*
X94300Y136801D01*
Y138907D01*
X89095Y144112D01*
Y159633D01*
X82428Y166300D01*
X78332D01*
X76947Y164915D01*
X73525D01*
X72300Y163690D01*
Y159400D01*
G01X73550Y166680D02*
X72284Y165414D01*
X68114D01*
X65935Y163235D01*
Y156064D01*
X66899Y155100D01*
X71455D01*
X71498Y155105D01*
X71537Y155137D01*
X74400Y158000D01*
Y160628D01*
X78842Y165070D01*
X81918D01*
X87865Y159123D01*
Y142732D01*
X87442Y142309D01*
X87409Y142269D01*
X87406Y142262D01*
X87405Y142252D01*
Y142205D01*
X87401Y142201D01*
X87400Y142191D01*
Y134345D01*
X87405Y134302D01*
X87437Y134263D01*
X88967Y132733D01*
X89002Y132705D01*
X89045Y132700D01*
X93500D01*
X99050Y127150D01*
Y124250D01*
X103300Y120000D01*
Y91599D01*
X104799Y90100D01*
X109899D01*
X113564Y93765D01*
X124036D01*
X128101Y89700D01*
X134700D01*
X139900Y84500D01*
X142752D01*
X147016Y86266D01*
X150940Y90190D01*
Y97986D01*
X158244Y105290D01*
X162890D01*
X164910Y107310D01*
X194060D01*
X195000Y106370D01*
Y101253D01*
X200618Y95635D01*
X212533D01*
X214294Y93874D01*
X232222D01*
X234176Y91920D01*
X239660D01*
G01X71146Y186489D02*
Y184253D01*
X73519Y181880D01*
Y180068D01*
X74552Y179035D01*
X76364D01*
X77100Y178299D01*
Y174447D01*
X80696Y170851D01*
X83099D01*
X92900Y161050D01*
Y146162D01*
X95659Y143403D01*
X99830D01*
X115422Y127811D01*
X126515D01*
X138654Y115672D01*
X142871D01*
X146261Y119062D01*
X169562D01*
X173325Y122825D01*
X189423D01*
X191482Y124884D01*
Y129294D01*
G01X204120Y132294D02*
X202124Y134290D01*
X194590D01*
X193860Y133560D01*
Y125521D01*
X189934Y121595D01*
X173895D01*
X166300Y114000D01*
X152301D01*
X149201Y110900D01*
X139472D01*
X131129Y119243D01*
X127381D01*
X121359Y125265D01*
X109938D01*
X105000Y130203D01*
Y132401D01*
X98001Y139400D01*
X95548D01*
X90325Y144623D01*
Y160144D01*
X82866Y167603D01*
X78356D01*
X76291Y169668D01*
X72978D01*
X71246Y171400D01*
X68090D01*
X66799Y172691D01*
Y178739D01*
X66800Y178740D01*
Y182540D01*
X69381Y185121D01*
Y188581D01*
X69791Y188991D01*
X71368D01*
X71370Y188993D01*
G01X151800Y116500D02*
X149204Y113904D01*
X148496D01*
X147958Y114442D01*
X137836D01*
X131753Y120525D01*
X127839D01*
X121783Y126581D01*
X114912D01*
X99320Y142173D01*
X95149D01*
X91555Y145767D01*
Y160655D01*
X83317Y168893D01*
X79455D01*
X71124Y177224D01*
Y178565D01*
G01X173000Y170200D02*
X172025Y169225D01*
X150525D01*
X136047Y154747D01*
X107252D01*
X100729Y161270D01*
X97757D01*
X84300Y174727D01*
Y183502D01*
X75702Y192100D01*
X67551D01*
X67386Y191935D01*
G01X184645Y169197D02*
X183086Y167638D01*
X180829D01*
X178339Y165148D01*
X155991D01*
X153191Y162348D01*
X151255D01*
X150603Y163000D01*
X145700D01*
X136517Y153817D01*
X106783D01*
X100260Y160340D01*
X97302D01*
X83354Y174288D01*
X81111D01*
X79700Y175699D01*
Y186500D01*
X75400Y190800D01*
X69221D01*
X67486Y189065D01*
Y188977D01*
G01X174436Y132394D02*
X173740D01*
X171346Y130000D01*
X168340D01*
X167875Y130465D01*
X165965D01*
X165195Y129695D01*
X164968Y129147D01*
Y126368D01*
X161155Y122555D01*
X151445D01*
X150584Y123416D01*
Y126429D01*
X149551Y127462D01*
X142825D01*
X141895Y128392D01*
X138508D01*
X122267Y144633D01*
X96169D01*
X94130Y146672D01*
Y161560D01*
X82952Y172738D01*
X80913D01*
X78430Y175221D01*
Y184670D01*
X76610Y186490D01*
X74046D01*
G01X184645Y181795D02*
X182961Y180111D01*
X178089D01*
X173350Y184850D01*
X167750D01*
X165000Y187600D01*
X158000D01*
X153000Y192600D01*
X149555D01*
X144448Y190484D01*
X141823Y187859D01*
X124730D01*
X121550Y184679D01*
Y176718D01*
X112282Y167450D01*
X100397D01*
X90548Y177299D01*
Y194118D01*
X83766Y200900D01*
X71600D01*
G01X209842Y225852D02*
X208168Y224178D01*
Y221565D01*
X207828Y221225D01*
X205827D01*
X205128Y220526D01*
Y218343D01*
X203780Y216995D01*
X199196D01*
X194366Y212165D01*
Y196673D01*
X190793Y193100D01*
X190400D01*
X187030Y189730D01*
X184130D01*
X182960Y188560D01*
Y187488D01*
X182102Y186630D01*
X175070D01*
X174230Y187470D01*
X168230D01*
X163453Y192247D01*
X156253D01*
X153900Y194600D01*
X149163D01*
X143648Y192316D01*
X141732Y190400D01*
X137900D01*
X134572Y193728D01*
X127967D01*
X119690Y185451D01*
Y177490D01*
X111510Y169310D01*
X101171D01*
X92408Y178073D01*
Y194890D01*
X83148Y204150D01*
X75750D01*
X75090Y204810D01*
X72150D01*
G01X76670Y208772D02*
X81672D01*
X97922Y225022D01*
X101659Y226570D01*
X107778D01*
X111744Y224927D01*
X114122Y223338D01*
X118800Y218660D01*
Y202900D01*
X124600Y197100D01*
X126999D01*
X128999Y199100D01*
X140582D01*
X140903Y199421D01*
G01X125700Y183700D02*
X124410Y182410D01*
Y175630D01*
X113440Y164660D01*
X99238D01*
X87758Y176140D01*
Y188158D01*
X78016Y197900D01*
X69599D01*
X66489Y201010D01*
X64050D01*
G01X72500Y214000D02*
Y217728D01*
X73851Y219079D01*
X82587D01*
X89208Y225700D01*
X93744D01*
X95901Y227857D01*
X100979Y229960D01*
X108868D01*
X112899Y228291D01*
X116312Y226010D01*
X121322Y221000D01*
X127102D01*
X130602Y224500D01*
X133064D01*
X134158Y223406D01*
X135624D01*
X138318Y226100D01*
X142100D01*
X142174Y226026D01*
X143826D01*
X145500Y227700D01*
G01X73011Y246365D02*
Y247641D01*
X74965Y249595D01*
X81151D01*
X86221Y254665D01*
X92033D01*
X99394Y247304D01*
X111487D01*
X112478Y248295D01*
X114702D01*
X116267Y246730D01*
X120068D01*
X121633Y248295D01*
X128265D01*
X137481Y239079D01*
X147291D01*
X150370Y236000D01*
X151690D01*
X153200Y237510D01*
Y241213D01*
X156320Y244333D01*
X169303D01*
X171766Y241870D01*
X190530D01*
X195600Y236800D01*
Y224900D01*
X194900Y224200D01*
X189291D01*
X187794Y222703D01*
G01X68800Y253300D02*
X70345Y251755D01*
X80255D01*
X88490Y259990D01*
X91532D01*
X92565Y258957D01*
Y257189D01*
X100290Y249464D01*
X110591D01*
X111582Y250455D01*
X115598D01*
X117163Y248890D01*
X119172D01*
X121067Y250785D01*
X128832D01*
X138378Y241239D01*
X146140D01*
X146900Y241999D01*
Y243600D01*
X150370Y247070D01*
X170190D01*
X171490Y245770D01*
X186810D01*
X191475Y250435D01*
X196920D01*
X197881Y250833D01*
X202460Y255412D01*
Y258370D01*
X201360Y259470D01*
X197020D01*
X187680Y268810D01*
Y273890D01*
X190190Y276400D01*
X204921D01*
X217491Y288970D01*
X229970D01*
X234500Y293500D01*
G01X77437Y262760D02*
X77817Y263140D01*
X84732D01*
X85422Y262450D01*
X92552D01*
X95160Y259842D01*
Y258081D01*
X101317Y251924D01*
X109570D01*
X110561Y252915D01*
X115715D01*
X117230Y254430D01*
X120020D01*
G01X169077Y308677D02*
X167259Y310495D01*
X157371D01*
X154976Y308100D01*
X127540D01*
X126280Y306840D01*
X109571D01*
X97970Y295239D01*
Y293470D01*
X85800Y281300D01*
X77951D01*
X77016Y282235D01*
X65340D01*
X65100Y282475D01*
G01X75870Y290700D02*
X77076Y289494D01*
X78406Y288943D01*
X81544D01*
X99990Y307389D01*
Y307900D01*
G01X226100Y325065D02*
X225565Y325600D01*
X215655D01*
X212355Y322300D01*
X207099D01*
X203199Y326200D01*
X192627D01*
X188163Y321736D01*
X180429D01*
X178100Y324065D01*
X169091D01*
X167461Y325695D01*
X150077D01*
X147402Y323020D01*
X136792D01*
X136362Y322590D01*
X128511D01*
X126700Y324401D01*
Y325632D01*
X125132Y327200D01*
X113534D01*
X110020Y330714D01*
X104513D01*
X102760Y328961D01*
Y328301D01*
X99770Y325311D01*
Y323399D01*
X95001Y318630D01*
X79771D01*
X78301Y320100D01*
X73500D01*
X68500Y325100D01*
G01X75056Y362173D02*
X76683Y363800D01*
X83500D01*
X86500Y366800D01*
X107550D01*
X111950Y371200D01*
G01X122047Y372260D02*
X117740D01*
X114480Y375520D01*
X108180D01*
X102760Y370100D01*
X73390D01*
X71906Y371584D01*
G01X177500Y369100D02*
X175500Y367100D01*
X135800D01*
X132485Y370415D01*
X118385D01*
X114280Y374520D01*
X108780D01*
X103160Y368900D01*
X71441D01*
X68757Y371584D01*
G01X71906Y374733D02*
X73539Y373100D01*
X103999D01*
X109399Y378500D01*
X110900D01*
G01X283664Y379236D02*
X278840Y384060D01*
X254999D01*
X252989Y382050D01*
X247293D01*
X241033Y388310D01*
X232400D01*
X231870Y387780D01*
X227430D01*
X224470Y390740D01*
X222620D01*
X212240Y380360D01*
X211930D01*
X211840Y380270D01*
X189027D01*
X188132Y381165D01*
X179082D01*
X166920Y393327D01*
X148484D01*
X144622Y389465D01*
X137695D01*
X134711Y392449D01*
X129948D01*
X128032Y394365D01*
X127222D01*
X125222Y396365D01*
X116234D01*
X112699Y399900D01*
X94440D01*
X91930Y402410D01*
X84275D01*
X83974Y402711D01*
X72539D01*
X68750Y406500D01*
X66500D01*
X65200Y407800D01*
Y409700D01*
X66319Y410819D01*
Y413492D01*
G01X285191Y390840D02*
X283093D01*
X279393Y387140D01*
X253941D01*
X242501Y398580D01*
X234870D01*
X232800Y396510D01*
X219400D01*
X216390Y393500D01*
X197228D01*
X191103Y387375D01*
X189318D01*
X175509Y401184D01*
X168937D01*
X164770Y397017D01*
X148282D01*
X146999Y398300D01*
X142617D01*
X142252Y397935D01*
X140638D01*
X139103Y396400D01*
X134067D01*
X132782Y397685D01*
X127382D01*
X126242Y398825D01*
X117033D01*
X114020Y401838D01*
X95982D01*
X92950Y404870D01*
X85295D01*
X84994Y405171D01*
X73649D01*
X71465Y407355D01*
Y409535D01*
X70435Y410565D01*
X68765D01*
X67000Y408800D01*
G01X69700D02*
Y407380D01*
X73139Y403941D01*
X84484D01*
X84785Y403640D01*
X92440D01*
X95280Y400800D01*
X113317D01*
X116522Y397595D01*
X125732D01*
X126872Y396455D01*
X132272D01*
X133305Y395422D01*
X133478D01*
X138205Y390695D01*
X144112D01*
X147974Y394557D01*
X167430D01*
X179592Y382395D01*
X188642D01*
X189537Y381500D01*
X211330D01*
X222080Y392250D01*
X234460D01*
X236958Y389752D01*
X241628D01*
X247890Y383490D01*
X251710D01*
X253860Y385640D01*
X279699D01*
X283000Y388941D01*
X285872D01*
X286309Y389378D01*
X287630D01*
G01X77860Y408678D02*
Y409590D01*
X84600Y416330D01*
X99670D01*
X102265Y413735D01*
Y409237D01*
X105902Y405600D01*
X117278D01*
X119611Y403267D01*
X128934D01*
X131931Y400270D01*
X134930D01*
X135300Y399900D01*
G01X189054Y397500D02*
X182439Y404115D01*
X137984D01*
X137214Y404885D01*
X130788D01*
X130400Y404497D01*
X123191D01*
X122400Y405288D01*
Y406904D01*
X121364Y407940D01*
X118340D01*
X117300Y406900D01*
X107250D01*
X105864Y408286D01*
Y412994D01*
X100513Y418345D01*
X74032D01*
X69139Y413452D01*
G01X190050Y389140D02*
Y389258D01*
X176423Y402885D01*
X168386D01*
X164301Y398800D01*
X154463D01*
X153263Y400000D01*
X153262D01*
X151607Y401655D01*
X140978D01*
X139665Y400342D01*
Y398768D01*
X138527Y397630D01*
X135014D01*
X133729Y398915D01*
X127892D01*
X126752Y400055D01*
X117543D01*
X114530Y403068D01*
X96492D01*
X93460Y406100D01*
X85805D01*
X85504Y406401D01*
X76898D01*
X76000Y407299D01*
Y411100D01*
X74782Y412318D01*
Y413800D01*
G01X153079Y412000D02*
X152235Y412844D01*
Y415666D01*
X150952Y416949D01*
X137332D01*
X135032Y414649D01*
X133568D01*
X130307Y417910D01*
X120768D01*
X118705Y419973D01*
Y424763D01*
X112628Y430840D01*
X101980D01*
X97610Y426470D01*
Y424023D01*
X95622Y422035D01*
X69648D01*
X69030Y422653D01*
G01X156101Y425100D02*
Y423091D01*
X154020Y421010D01*
X146633D01*
X140343Y427300D01*
X121418D01*
X112243Y436475D01*
X102774D01*
X99464Y433165D01*
X72665D01*
X71200Y431700D01*
G01X281300Y416200D02*
X276522Y420978D01*
X274030D01*
X268708Y426300D01*
X252699D01*
X241899Y437100D01*
X232400D01*
X231135Y438365D01*
X218715D01*
X218615Y438265D01*
X209264D01*
X202904Y440900D01*
X189848D01*
X186358Y437410D01*
X172400D01*
X171192Y438618D01*
X148964D01*
X142957Y436130D01*
X114752D01*
X112877Y438005D01*
X101705D01*
X98395Y434695D01*
X76005D01*
X72800Y437900D01*
G01X89170Y141540D02*
X92700Y138010D01*
Y136200D01*
X99400Y129500D01*
X103200D01*
X113600Y119100D01*
X125000D01*
X127300Y116800D01*
X131736D01*
X139336Y109200D01*
X162462D01*
X163762Y110500D01*
X171100D01*
X174600Y114000D01*
G01X144500Y169570D02*
X136730Y161800D01*
X134600D01*
X128800Y156000D01*
X107901D01*
X101401Y162500D01*
X98336D01*
X85598Y175238D01*
Y187203D01*
X81989Y190812D01*
X80788D01*
G01X82370Y197010D02*
X83090D01*
X88688Y191412D01*
Y176526D01*
X99624Y165590D01*
X113054D01*
X123410Y175946D01*
Y183907D01*
X125502Y185999D01*
X144401D01*
X147300Y183100D01*
X156100D01*
X159615Y179585D01*
X161972D01*
X163157Y178400D01*
X170213D01*
X174569Y180202D01*
G01X142085Y230549D02*
X141629D01*
X141361Y230817D01*
X139717D01*
X138700Y231834D01*
X128165D01*
X127000Y232999D01*
Y243700D01*
X123635Y247065D01*
X122143D01*
X120578Y245500D01*
X115757D01*
X114192Y247065D01*
X112988D01*
X111997Y246074D01*
X98824D01*
X96033Y248865D01*
X95335D01*
X91300Y252900D01*
G01X121200Y234890D02*
Y241338D01*
X118573Y243965D01*
X115965D01*
X115405Y243405D01*
X112857D01*
X111418Y244844D01*
X81244D01*
X80300Y243900D01*
Y243700D01*
G01X106600Y253689D02*
X103053D01*
X93062Y263680D01*
X86720D01*
X83500Y266900D01*
G01X119105Y251511D02*
X118931Y251685D01*
X111071D01*
X110080Y250694D01*
X100806D01*
X93795Y257705D01*
Y259467D01*
X92042Y261220D01*
X87006D01*
X84016Y258230D01*
G01X138600Y295900D02*
X129974Y287274D01*
X110022D01*
X108830Y286082D01*
Y281585D01*
X109269Y281146D01*
Y278910D01*
X104059Y273700D01*
X98200D01*
X91500Y267000D01*
G01X312300Y340700D02*
X309600Y343400D01*
X298500D01*
X293500Y338400D01*
Y315199D01*
X292101Y313800D01*
X259545D01*
X258880Y314465D01*
X253545D01*
X251255Y312175D01*
X246171D01*
X243546Y314800D01*
X243540D01*
X243530Y314810D01*
X237297D01*
X236277Y315830D01*
X226670D01*
X216602Y305762D01*
X212397D01*
X210259Y307900D01*
X199901D01*
X198731Y309070D01*
X194231D01*
X192301Y311000D01*
X183489D01*
X179693Y307204D01*
X177492Y306292D01*
X173961D01*
X168458Y311795D01*
X156931D01*
X155046Y309910D01*
X147449D01*
X144959Y312400D01*
X141222D01*
X138152Y309330D01*
X127030D01*
X125770Y308070D01*
X109061D01*
X96740Y295749D01*
Y294702D01*
X96739Y294699D01*
X92010Y289970D01*
X87791D01*
X81791Y283970D01*
X78600D01*
G01X92300Y282100D02*
X101900Y291700D01*
X102999D01*
X115349Y304050D01*
X127438D01*
X128288Y304900D01*
X169700D01*
X170550Y304050D01*
G01X78770Y290708D02*
X81569D01*
X91800Y300939D01*
Y312201D01*
X93699Y314100D01*
X95399D01*
X102699Y321400D01*
X103900D01*
X104770Y322270D01*
Y324590D01*
X105680Y325500D01*
X107970D01*
X112110Y321360D01*
X136872D01*
X137302Y321790D01*
X147912D01*
X150587Y324465D01*
X152054D01*
X155000Y321519D01*
Y321100D01*
G01X81355Y346425D02*
X83376D01*
X85166Y344635D01*
X96565D01*
X98300Y342900D01*
X108200D01*
X108800Y343500D01*
X130500D01*
X136401Y349401D01*
Y353901D01*
X141000Y358500D01*
G01X161154Y376704D02*
Y375655D01*
X158999Y373500D01*
X148456D01*
X143591Y378365D01*
X129286D01*
X123358Y375910D01*
X118170D01*
X111580Y382500D01*
X92233D01*
X90766Y381033D01*
G01X165501Y382800D02*
Y376701D01*
X161370Y372570D01*
X148070D01*
X146900Y373740D01*
X140467D01*
X139604Y374603D01*
X134296D01*
X132394Y376505D01*
X129659D01*
X123731Y374050D01*
X117964D01*
X111544Y380470D01*
X104469D01*
X100417Y376418D01*
X89082D01*
X87617Y377883D01*
G01X90766Y390481D02*
X91547Y389700D01*
X111600D01*
X119400Y381900D01*
Y379900D01*
X120600Y378700D01*
X122799D01*
X128726Y381155D01*
X151055D01*
X152500Y382600D01*
G01X90766Y387332D02*
X90781D01*
X92264Y388815D01*
X107331D01*
X118376Y377770D01*
X122984D01*
X128912Y380225D01*
X145376D01*
X145436Y380165D01*
X152832D01*
X153865Y379132D01*
Y375470D01*
X154800Y374535D01*
X157178D01*
X158200Y375557D01*
Y381400D01*
G01X92360Y394175D02*
X94435Y392100D01*
X112300D01*
X117230Y387170D01*
X121075D01*
X124426Y385781D01*
X127859D01*
X130025Y383615D01*
X147048D01*
X148268Y384835D01*
X153465D01*
X155200Y383100D01*
Y377400D01*
X156300Y376300D01*
G01X89210Y394175D02*
X90675Y395640D01*
X93159D01*
X95399Y393400D01*
X112901D01*
X118201Y388100D01*
X121260D01*
X123704Y387088D01*
X127869D01*
X130412Y384545D01*
X146662D01*
X149442Y387325D01*
X150820D01*
G01X96030Y409400D02*
X95000D01*
X91700Y412700D01*
X84300D01*
X81552Y409952D01*
Y409660D01*
G01X224000Y449100D02*
X220350Y452750D01*
X197450D01*
X194660Y449960D01*
X190058D01*
X183198Y443100D01*
X174900D01*
X161600Y456400D01*
X152800D01*
X140590Y444190D01*
X118900D01*
X112160Y450930D01*
X100390D01*
X97990Y448530D01*
X91720D01*
X86820Y443630D01*
X81130D01*
X79010Y445750D01*
G01X293773Y73530D02*
X291166Y70923D01*
X264864D01*
X255272Y61331D01*
X234719D01*
X223878Y72172D01*
X217903D01*
X216891Y73184D01*
X173619D01*
X168975Y77828D01*
X163508D01*
X161196Y75516D01*
Y73524D01*
X157277Y69605D01*
X148830D01*
X144355Y65130D01*
X124986D01*
X119670Y70446D01*
X110908D01*
X110024Y71330D01*
X107450D01*
X107124Y71004D01*
G01X189700Y140400D02*
X186960D01*
X181990Y135430D01*
X163746D01*
X159284Y130968D01*
X155674D01*
X154506Y129800D01*
X150693D01*
X150571Y129922D01*
X144418D01*
X141127Y133213D01*
Y138400D01*
X144100Y141373D01*
Y146800D01*
X139260Y151640D01*
X97897D01*
X95944Y149687D01*
G01X200680Y257540D02*
X198005Y254865D01*
Y252697D01*
X197186Y251878D01*
X196672Y251665D01*
X190965D01*
X186300Y247000D01*
X172000D01*
X170700Y248300D01*
X150600D01*
X148330Y250570D01*
X132687D01*
X129287Y253970D01*
X125507D01*
X123282Y256195D01*
X113423D01*
X113018Y256600D01*
X105301D01*
X101500Y260401D01*
Y261601D01*
X98000Y265101D01*
Y268375D01*
X101165Y271540D01*
X104955D01*
X111600Y278185D01*
Y284000D01*
G01X107200Y265000D02*
X107400Y265083D01*
X107907Y266306D01*
X110486Y268885D01*
X131114D01*
X138239Y261760D01*
X153889D01*
X154349Y261300D01*
X181279D01*
X182782Y259797D01*
Y258206D01*
X182198Y256796D01*
X180552Y255150D01*
X179846D01*
G01X168300Y301100D02*
Y301770D01*
X166100Y303970D01*
X128674D01*
X127824Y303120D01*
X119720D01*
X118600Y302000D01*
Y297968D01*
X122365Y294203D01*
Y290730D01*
X120769Y289134D01*
X109250D01*
X106100Y285984D01*
Y282900D01*
G01X100700Y293600D02*
X103199D01*
X114579Y304980D01*
X127052D01*
X127972Y305900D01*
X159700D01*
X161400Y307600D01*
G01X291300Y315900D02*
X285340D01*
X284540Y315100D01*
X267479D01*
X264997Y317582D01*
X253182D01*
X250235Y314635D01*
X247191D01*
X246158Y315668D01*
Y318642D01*
X244395Y320405D01*
X236605D01*
X234490Y318290D01*
X225520D01*
X217281Y310051D01*
X215487D01*
X214768Y310770D01*
X208459D01*
X202819Y316410D01*
X193007D01*
X190107Y313510D01*
X182517D01*
X178297Y309290D01*
X176998Y308752D01*
X174981D01*
X169528Y314205D01*
X169393D01*
X165803Y317795D01*
X160409D01*
X157814Y315200D01*
X155540D01*
X153640Y313300D01*
X149199D01*
X146899Y315600D01*
X146739D01*
X146309Y316030D01*
X139690D01*
X139260Y315600D01*
X104390D01*
X99990Y311200D01*
G01X94400Y311100D02*
X94439D01*
X100769Y317430D01*
X102740D01*
X103370Y318060D01*
X138240D01*
X138670Y318490D01*
X147329D01*
X147759Y318060D01*
X147919D01*
X148271Y317708D01*
X149051Y318488D01*
X151535D01*
X152593Y317430D01*
X154290D01*
X154520Y317660D01*
X156391D01*
X159496Y320765D01*
X176732D01*
X179061Y318436D01*
X189531D01*
X193995Y322900D01*
X201831D01*
X206961Y317770D01*
X212493D01*
X213288Y318565D01*
X220665D01*
X222850Y320750D01*
X233450D01*
X236100Y323400D01*
X243010D01*
G01X247923Y319000D02*
X245288Y321635D01*
X236095D01*
X233980Y319520D01*
X225009D01*
X219870Y314381D01*
X208610D01*
X201321Y321670D01*
X194505D01*
X190041Y317206D01*
X175006D01*
X173235Y315435D01*
X169903D01*
X166313Y319025D01*
X159496D01*
X156901Y316430D01*
X155030D01*
X154800Y316200D01*
X152083D01*
X151025Y317258D01*
X149561D01*
X148503Y316200D01*
X148039D01*
X147409Y316830D01*
X147249D01*
X146819Y317260D01*
X139180D01*
X138750Y316830D01*
X103880D01*
X103250Y316200D01*
X101279D01*
X96800Y311721D01*
Y309600D01*
X94400Y307200D01*
G01X286372Y320700D02*
X265897D01*
X265332Y321265D01*
X263868D01*
X263303Y320700D01*
X251899D01*
X246790Y325809D01*
X236175D01*
X232766Y322400D01*
X221600D01*
X219415Y320215D01*
X212604D01*
X211809Y319420D01*
X207645D01*
X202515Y324550D01*
X193311D01*
X188847Y320086D01*
X179745D01*
X177416Y322415D01*
X158812D01*
X155707Y319310D01*
X153836D01*
X153606Y319080D01*
X153277D01*
X152219Y320138D01*
X148367D01*
X148191Y319962D01*
X148013Y320140D01*
X137986D01*
X137556Y319710D01*
X110434D01*
X106852Y323292D01*
G01X138700Y376600D02*
X137865Y377435D01*
X129474D01*
X123543Y374980D01*
X118067D01*
X111847Y381200D01*
X103300D01*
X101668Y379568D01*
X95381D01*
X93916Y381033D01*
G01X152100Y378400D02*
X145716D01*
X144821Y379295D01*
X129099D01*
X123172Y376840D01*
X118273D01*
X109313Y385800D01*
X95448D01*
X93916Y387332D01*
G01X134300Y416414D02*
X133670D01*
X127884Y422200D01*
X121008D01*
X119935Y423273D01*
Y425865D01*
X113700Y432100D01*
X101500D01*
X95845Y426445D01*
Y424755D01*
G01X106700Y447730D02*
X110670D01*
X116690Y441710D01*
X143270D01*
X148875Y447315D01*
X167205D01*
X173880Y440640D01*
X184220D01*
X190685Y447105D01*
X196096D01*
X199261Y450270D01*
X218593D01*
X222302Y446561D01*
X228497Y443995D01*
X240006D01*
X241471Y442530D01*
X247280D01*
X252090Y437720D01*
X274411D01*
X278409Y433722D01*
G01X109121Y69500D02*
X119300D01*
X124600Y64200D01*
X144741D01*
X148841Y68300D01*
X171854D01*
X175792Y72238D01*
X216499D01*
X217511Y71226D01*
X223486D01*
X234327Y60385D01*
X255664D01*
X265256Y69977D01*
X293814D01*
X297575Y73738D01*
G01X278300Y95019D02*
X272169D01*
X270290Y93140D01*
Y91290D01*
X259000Y80000D01*
X246266D01*
X242266Y84000D01*
X236423D01*
X233848Y86575D01*
X227801D01*
X226981Y87395D01*
X200906D01*
X192576Y95725D01*
X181475D01*
X180000Y97200D01*
Y100000D01*
X179500Y100500D01*
X174600D01*
X173600Y99500D01*
X160644D01*
X156730Y95586D01*
Y86433D01*
X147532Y77235D01*
X131565D01*
X124285Y84515D01*
X121627D01*
X119162Y82050D01*
X110950D01*
G01X111075Y104600D02*
Y96425D01*
X111805Y95695D01*
X129000D01*
X129500Y95195D01*
Y91475D01*
G01X120724Y108937D02*
X133042Y96619D01*
X134623Y92803D01*
X140926Y86500D01*
X141100D01*
G01X212991Y166047D02*
X211466Y164522D01*
Y152906D01*
X209392Y150832D01*
Y150828D01*
X200284Y141720D01*
X200280D01*
X195965Y137405D01*
X187445D01*
X184910Y134870D01*
Y129290D01*
X182595Y126975D01*
X176197D01*
X174660Y126338D01*
X168614Y120292D01*
X145291D01*
X141901Y116902D01*
X139165D01*
X127026Y129041D01*
X116689D01*
X109670Y136060D01*
G01X175196Y200655D02*
Y201733D01*
X168905Y208024D01*
X164299D01*
X162975Y206700D01*
X158700D01*
X158300Y207100D01*
X142300D01*
X139900Y204700D01*
X133800D01*
X131993Y206507D01*
X122893D01*
X121500Y207900D01*
Y210100D01*
X123120Y211720D01*
Y213088D01*
G01X109800Y264928D02*
X114703D01*
X116966Y262665D01*
X123166D01*
X124431Y263930D01*
X132366D01*
X136866Y259430D01*
X147012D01*
X147672Y258770D01*
Y257490D01*
X148332Y256830D01*
X149342D01*
X150002Y257490D01*
Y258770D01*
X150662Y259430D01*
X152559D01*
X155224Y256765D01*
X159666D01*
X161732Y258831D01*
X180452D01*
X180458Y258825D01*
G01X111600Y262730D02*
X112630Y261700D01*
X114635D01*
X116000Y260335D01*
X124436D01*
X125701Y261600D01*
X131400D01*
X137165Y255835D01*
X137166D01*
X138501Y254500D01*
X151163D01*
X154786Y253000D01*
X165524D01*
X169025Y256501D01*
X175905D01*
X179586Y252820D01*
X181930D01*
X184212Y255102D01*
X185112Y257277D01*
Y259690D01*
X185830Y260408D01*
X187190D01*
X187850Y261068D01*
Y262078D01*
X187190Y262738D01*
X185360D01*
X184700Y263398D01*
Y264400D01*
X184200Y264900D01*
G01X120070Y273700D02*
Y276170D01*
X127680Y283780D01*
X137422D01*
X147192Y274010D01*
X162210D01*
X172775Y284575D01*
X199293D01*
X205318Y290600D01*
X214579D01*
X222004Y298025D01*
X238826D01*
X242767Y301966D01*
X251982D01*
X252718Y302702D01*
X266499D01*
X270296Y298905D01*
X271624D01*
X272309Y298220D01*
Y297385D01*
X272994Y296700D01*
X273964D01*
X274649Y297385D01*
Y298220D01*
X275334Y298905D01*
X276304D01*
X276989Y298220D01*
Y297385D01*
X277674Y296700D01*
X278644D01*
X279329Y297385D01*
Y298220D01*
X280014Y298905D01*
X283033D01*
X285724Y301596D01*
X287507D01*
G01X115000Y273700D02*
X126070Y284770D01*
X137833D01*
X147603Y275000D01*
X161799D01*
X172489Y285690D01*
X199006D01*
X204906Y291590D01*
X214168D01*
X221593Y299015D01*
X238415D01*
X242356Y302956D01*
X251571D01*
X252307Y303692D01*
X271070D01*
X274762Y300000D01*
X277800D01*
X286860Y309060D01*
X289939D01*
G01X129800Y325800D02*
Y327900D01*
X127400Y330300D01*
X123200D01*
X115600Y337900D01*
G01X226710Y364815D02*
X221915D01*
X217830Y360730D01*
X210590D01*
X204655Y354795D01*
X196705D01*
X185805Y365695D01*
X130995D01*
X124500Y359200D01*
X121200D01*
G01X119026Y393332D02*
X121371D01*
X121868Y392835D01*
X123668D01*
X124910Y391593D01*
X126879Y390778D01*
X129399D01*
X131942Y388235D01*
X145132D01*
X148994Y392097D01*
X166410D01*
X180872Y377635D01*
X190305D01*
X191470Y378800D01*
X217700D01*
X223390Y384490D01*
X233790D01*
G01X116632Y411500D02*
Y413552D01*
X117300Y414220D01*
X122667D01*
X128402Y408485D01*
X131628D01*
X132768Y407345D01*
X134232D01*
X134392Y407505D01*
X185211D01*
X192316Y400400D01*
X209600D01*
X210531Y401331D01*
X214097D01*
X217688Y397740D01*
X231980D01*
X234260Y400020D01*
X243190D01*
X254550Y388660D01*
X279320D01*
X283397Y392737D01*
X287776D01*
X296837Y383676D01*
Y371557D01*
X296780Y371500D01*
G01X108500Y408680D02*
X108990Y409170D01*
X121875D01*
X121900Y409145D01*
X124686D01*
X127716Y406115D01*
X138330D01*
X139100Y405345D01*
X184315D01*
X192880Y396780D01*
X195800D01*
G01X121700Y424005D02*
X123465Y425770D01*
X139650D01*
X146011Y419409D01*
X160692D01*
X163129Y418400D01*
X177960D01*
X181125Y421565D01*
X188175D01*
X191240Y418500D01*
X197899D01*
X205885Y410514D01*
X209686D01*
X215600Y404600D01*
X217499D01*
X220134Y401965D01*
Y400780D01*
G01X321800Y60055D02*
Y61370D01*
X319200Y63970D01*
X300520D01*
X290315Y53765D01*
X258765D01*
X255000Y50000D01*
X247235D01*
X244000Y53235D01*
X215622D01*
X213001Y55856D01*
X194787D01*
X185866Y46935D01*
X152434D01*
X146952Y52417D01*
Y59570D01*
X146622Y59900D01*
X133000D01*
G01X182103Y132294D02*
X181754D01*
X180049Y130589D01*
X173819D01*
X172660Y129430D01*
Y125655D01*
X168227Y121222D01*
X146577D01*
X141327Y126472D01*
X135580D01*
X134400Y127652D01*
G01X184645Y172347D02*
X183104Y173888D01*
X177786D01*
X176810Y172912D01*
Y171518D01*
X176109Y170817D01*
X174578D01*
X172203Y173192D01*
X142208D01*
X140300Y175100D01*
X135300D01*
G01X124779Y201633D02*
X138733D01*
X142700Y205600D01*
X153801D01*
X154700Y204701D01*
Y202400D01*
X157000Y200100D01*
Y198408D01*
X159528Y195880D01*
X164620D01*
X169165Y191335D01*
X174943D01*
X177208Y193600D01*
X182863D01*
X183523Y194260D01*
X183559D01*
X184645Y195346D01*
Y197506D01*
G01X128760Y273701D02*
Y280861D01*
X130689Y282790D01*
X137011D01*
X146781Y273020D01*
X162621D01*
X173186Y283585D01*
X202817D01*
X203987Y284755D01*
X206854D01*
X211589Y289490D01*
X214870D01*
X222415Y297035D01*
X239965D01*
X245000Y292000D01*
X248800D01*
X249500Y292700D01*
X251013D01*
X251698Y293385D01*
Y295915D01*
X252383Y296600D01*
X253353D01*
X254038Y295915D01*
Y293385D01*
X254723Y292700D01*
X271051D01*
X271906Y293555D01*
X283808D01*
X285207Y294954D01*
Y295922D01*
X284150Y296980D01*
Y297948D01*
X284837Y298635D01*
X285805D01*
X286862Y297577D01*
X287830D01*
X289939Y299686D01*
Y302961D01*
X287050Y305850D01*
G01X137083Y278045D02*
X137157Y278119D01*
X140281D01*
X146370Y272030D01*
X163032D01*
X170202Y279200D01*
X174300D01*
X176765Y276735D01*
X182135D01*
X183600Y278200D01*
X191200D01*
X193000Y280000D01*
X200633D01*
X204398Y283765D01*
X207265D01*
X212000Y288500D01*
X215281D01*
X222826Y296045D01*
X239554D01*
X245499Y290100D01*
X258778D01*
X260678Y288200D01*
X267952D01*
X272317Y292565D01*
X284219D01*
X289354Y297700D01*
X291000D01*
G01X197155Y314223D02*
X196278Y315100D01*
X193437D01*
X190617Y312280D01*
X183028D01*
X179341Y308593D01*
X179340Y308591D01*
X178997Y308248D01*
X178995Y308247D01*
X177245Y307522D01*
X174471D01*
X169018Y312975D01*
X168883D01*
X165293Y316565D01*
X160919D01*
X158324Y313970D01*
X156050D01*
X154150Y312070D01*
X148529D01*
X145799Y314800D01*
X140200D01*
X136890Y311490D01*
X125974D01*
X125584Y311100D01*
X124100D01*
G01X125900Y337600D02*
X129481D01*
X134836Y342955D01*
X144128D01*
X152983Y351810D01*
X172091D01*
X178635Y345266D01*
Y341076D01*
X180650Y339061D01*
X183867D01*
X188130Y334798D01*
X192098D01*
X194180Y336880D01*
X201562D01*
X204882Y340200D01*
X219800D01*
X224645Y335355D01*
X226555D01*
X230380Y339180D01*
X245404D01*
X253284Y331300D01*
X266301D01*
X273791Y338790D01*
X289540D01*
X290120Y339370D01*
G01X136100Y334000D02*
X143075Y340975D01*
X144950D01*
X150075Y346100D01*
X161518D01*
X162203Y345415D01*
Y343785D01*
X162888Y343100D01*
X163858D01*
X164543Y343785D01*
Y345415D01*
X165228Y346100D01*
X166198D01*
X166883Y345415D01*
Y343785D01*
X167568Y343100D01*
X168538D01*
X169223Y343785D01*
Y345415D01*
X169908Y346100D01*
X173700D01*
X176655Y343145D01*
Y340254D01*
X179828Y337081D01*
X183045D01*
X187308Y332818D01*
X192920D01*
X194640Y334538D01*
X202990D01*
X204580Y332948D01*
X205548D01*
X206235Y333635D01*
Y334603D01*
X204645Y336193D01*
Y337161D01*
X205684Y338200D01*
X207527D01*
X208212Y337515D01*
Y336285D01*
X208897Y335600D01*
X209867D01*
X210552Y336285D01*
Y337515D01*
X211237Y338200D01*
X218400D01*
X220010Y336590D01*
Y335622D01*
X218878Y334490D01*
Y333622D01*
X219565Y332935D01*
X220633D01*
X221665Y333967D01*
X222633D01*
X224039Y332561D01*
X229343D01*
X230779Y331125D01*
X232875D01*
X233649Y331899D01*
X235017D01*
X240318Y337200D01*
X245983D01*
X252873Y330310D01*
X267311D01*
X273781Y336780D01*
X278722D01*
X281972Y333530D01*
X287930D01*
X290000Y335600D01*
G01X133300Y334100D02*
X133500D01*
X141365Y341965D01*
X144539D01*
X149874Y347300D01*
X174200D01*
X177645Y343855D01*
Y340665D01*
X180239Y338071D01*
X183456D01*
X187719Y333808D01*
X192509D01*
X194591Y335890D01*
X201973D01*
X205273Y339190D01*
X218811D01*
X218901Y339100D01*
X219002D01*
X223737Y334365D01*
X227163D01*
X230749Y337951D01*
Y337950D01*
X230989Y338190D01*
X233910D01*
X235000Y337100D01*
Y335300D01*
G01X129776Y374500D02*
X135976Y368300D01*
X174202D01*
X177312Y371410D01*
X189490D01*
X198370Y362530D01*
Y357480D01*
X197450Y356560D01*
G01X123100Y390600D02*
X125640Y389548D01*
X128889D01*
X131432Y387005D01*
X145642D01*
X149504Y390867D01*
X165900D01*
X180362Y376405D01*
X190815D01*
X191980Y377570D01*
X218210D01*
X222920Y382280D01*
X232470D01*
G01X217390Y401340D02*
Y401350D01*
X216479Y402261D01*
X206639D01*
X203900Y405000D01*
Y410630D01*
X201495Y413035D01*
X187935D01*
X186500Y411600D01*
X158500D01*
X156700Y413400D01*
Y415870D01*
X154391Y418179D01*
X133221D01*
X127395Y424005D01*
X124500D01*
G01X129135Y410250D02*
X129760Y410875D01*
X134925D01*
X137065Y408735D01*
X185765D01*
X187900Y406600D01*
X193101D01*
X194500Y405201D01*
Y402600D01*
G01X128866Y433066D02*
Y434400D01*
X129366Y434900D01*
X143203D01*
X149210Y437388D01*
X151758D01*
X152418Y436728D01*
Y435660D01*
X153078Y435000D01*
X154098D01*
X154758Y435660D01*
Y436728D01*
X155418Y437388D01*
X159806D01*
X161094Y436100D01*
X162146D01*
X163434Y437388D01*
X164486D01*
X165774Y436100D01*
X166826D01*
X168114Y437388D01*
X170372D01*
X171580Y436180D01*
X186869D01*
X190189Y439500D01*
X202610D01*
X202688Y439532D01*
X205969Y438172D01*
X210306Y433835D01*
X217897D01*
X220200Y436138D01*
X225862D01*
X226830Y435170D01*
G01X135350Y433016D02*
X142560D01*
X147748Y435165D01*
X149235D01*
X150700Y433700D01*
X162333D01*
X165146Y434865D01*
X165852D01*
X166154Y434740D01*
X187170D01*
X190134Y437704D01*
X191332Y438200D01*
X202688D01*
X205272Y437129D01*
X209796Y432605D01*
X222405D01*
X222900Y433100D01*
X225000D01*
G01X287476Y396680D02*
Y398394D01*
X286400Y399470D01*
X272260D01*
X270500Y401230D01*
X233450D01*
X225940Y408740D01*
Y410400D01*
X222420Y413920D01*
X217360D01*
X211740Y419540D01*
X200870D01*
X195000Y425410D01*
X189910D01*
X188050Y423550D01*
X172000D01*
X168510Y420060D01*
X162990D01*
X160970Y422080D01*
Y424100D01*
X156030Y429040D01*
X129100D01*
X125930Y432210D01*
Y433110D01*
G01X145000Y90700D02*
X147482Y96692D01*
X157610Y106820D01*
X162246D01*
X164266Y108840D01*
X176917D01*
X185151Y112251D01*
X186891Y113991D01*
G01X138458Y146458D02*
X139000Y145916D01*
Y133600D01*
X143908Y128692D01*
X150061D01*
X151653Y127100D01*
X161090D01*
X163927Y129937D01*
X164430Y131151D01*
Y133440D01*
X165190Y134200D01*
X182500D01*
X186935Y138635D01*
X192775D01*
X194812Y140672D01*
Y141917D01*
X195845Y142950D01*
X199774D01*
X208162Y151338D01*
Y167517D01*
X209842Y169197D01*
G01X184000Y140500D02*
Y139180D01*
X181480Y136660D01*
X163158D01*
X158698Y132200D01*
X150000D01*
X145900Y136300D01*
Y155780D01*
X148660Y158540D01*
X159639D01*
X161199Y160100D01*
X174844D01*
X175196Y159748D01*
G01X143742Y203395D02*
X148295D01*
X149730Y201960D01*
Y199470D01*
X152100Y197100D01*
X154000D01*
X157600Y193500D01*
X163530D01*
X168530Y188500D01*
X175300D01*
X176579Y189779D01*
X182378D01*
X183180Y190581D01*
Y191851D01*
X184129Y192800D01*
X188600D01*
X193600Y197800D01*
Y206700D01*
X191800Y208500D01*
X189398D01*
X187794Y210104D01*
G01X151040Y237870D02*
Y240369D01*
X155934Y245263D01*
X169689D01*
X171422Y243530D01*
X186310D01*
X191985Y249205D01*
X197505D01*
X198338Y249550D01*
X203690Y254902D01*
Y258920D01*
X201910Y260700D01*
X197530D01*
X188910Y269320D01*
Y272208D01*
X191872Y275170D01*
X205431D01*
X208481Y278220D01*
X229280D01*
X231870Y275630D01*
X243455D01*
X246895Y272190D01*
X248680D01*
X249770Y271100D01*
X269723D01*
X272123Y268700D01*
Y264733D01*
X279528Y257328D01*
X293112D01*
X295520Y254920D01*
Y228840D01*
X300383Y223977D01*
X304913Y222100D01*
X315350D01*
X317110Y220340D01*
Y219140D01*
G01X300700Y341300D02*
X294800Y335400D01*
Y314700D01*
X292670Y312570D01*
X288630D01*
X281530Y305470D01*
X257190D01*
X254760Y307900D01*
X245220D01*
X244555Y308565D01*
X239121D01*
X238178Y307622D01*
X235198D01*
X234177Y308643D01*
X225023D01*
X216120Y299740D01*
X212461D01*
X208026Y304175D01*
X203297D01*
X200292Y301170D01*
X196400D01*
X187539Y292309D01*
X167291D01*
X163600Y296000D01*
X152503D01*
X147500Y290997D01*
Y289405D01*
G01X150293Y302117D02*
X156683D01*
X159621Y299179D01*
X165208D01*
X167897Y296490D01*
X174713D01*
X179161Y300938D01*
X179654Y301142D01*
X180580Y301525D01*
X188425D01*
X189300Y302400D01*
X199782D01*
X202787Y305405D01*
X208972D01*
X211445Y302932D01*
Y302496D01*
X212971Y300970D01*
X215610D01*
X224513Y309873D01*
X234687D01*
X235708Y308852D01*
X237668D01*
X239053Y310237D01*
Y311854D01*
X239549Y312350D01*
X242510D01*
X245630Y309230D01*
X255170D01*
X257700Y306700D01*
X265500D01*
X266300Y307500D01*
G01X142300Y336700D02*
X140400Y334800D01*
Y333021D01*
X142386Y331035D01*
X169081D01*
X170508Y329608D01*
X194252D01*
X195314Y330670D01*
X202316D01*
X203631Y329355D01*
X215993D01*
X216218Y329580D01*
X222478D01*
X222707Y329351D01*
X228011D01*
X229447Y327915D01*
X234207D01*
X234981Y328689D01*
X236349D01*
X241650Y333990D01*
X244651D01*
X251541Y327100D01*
X268900D01*
X271800Y330000D01*
X273400D01*
Y330001D01*
X273355D01*
G01X144800Y336700D02*
X146165Y338065D01*
X174516D01*
X176490Y336091D01*
X182634D01*
X186897Y331828D01*
X193331D01*
X194403Y332900D01*
X203227D01*
X204552Y331575D01*
X215072D01*
X215297Y331800D01*
X223399D01*
X223628Y331571D01*
X228932D01*
X230368Y330135D01*
X233286D01*
X234060Y330909D01*
X235428D01*
X240729Y336210D01*
X245572D01*
X252462Y329320D01*
X267979D01*
X274449Y335790D01*
X278311D01*
X285001Y329100D01*
X289100D01*
X289600Y328600D01*
Y322253D01*
G01X286372Y326768D02*
X285932D01*
X282488Y330212D01*
X281520D01*
X279838Y328530D01*
X278870D01*
X278183Y329217D01*
Y330185D01*
X279865Y331867D01*
Y332835D01*
X277900Y334800D01*
X274860D01*
X268390Y328330D01*
X252051D01*
X245161Y335220D01*
X241140D01*
X235839Y329919D01*
X234471D01*
X233697Y329145D01*
X229957D01*
X228521Y330581D01*
X223217D01*
X222988Y330810D01*
X215708D01*
X215483Y330585D01*
X204141D01*
X202826Y331900D01*
X194804D01*
X193742Y330838D01*
X186486D01*
X183224Y334100D01*
X144700D01*
G01X221000Y352000D02*
X210672D01*
X202542Y343870D01*
X193241D01*
X192032Y342661D01*
X189139D01*
X187730Y344070D01*
Y346470D01*
X171900Y362300D01*
X158592D01*
X152427Y356135D01*
X150065D01*
X149500Y356700D01*
G01X145703Y370700D02*
X146703Y369700D01*
X173862D01*
X176802Y372640D01*
X190773D01*
X192508Y370905D01*
X194095D01*
X197400Y367600D01*
G01X139200Y372510D02*
X146390D01*
X147700Y371200D01*
X173622D01*
X176292Y373870D01*
X191283D01*
X193018Y372135D01*
X195515D01*
X197400Y370250D01*
G01X139400Y392460D02*
X139935Y391925D01*
X143602D01*
X147464Y395787D01*
X178713D01*
X191469Y383031D01*
X191472Y383030D01*
X210810D01*
X221510Y393730D01*
X234430D01*
X235250Y394550D01*
X236670D01*
G01X200393Y219553D02*
X198846Y221100D01*
X186600D01*
X186200Y221500D01*
Y223600D01*
X185600Y224200D01*
X177800D01*
X174700Y227300D01*
X168100D01*
X164400Y231000D01*
X162700D01*
X161700Y230000D01*
Y221876D01*
X162200Y221376D01*
G01X163500Y229184D02*
Y223732D01*
X166689Y220543D01*
X168342D01*
X170299Y222500D01*
X175701D01*
X178648Y219553D01*
X181495D01*
G01X167200Y222600D02*
X168330Y223730D01*
X177170D01*
X179682Y221218D01*
X182980D01*
X184645Y219553D01*
G01X175300Y240000D02*
X172320D01*
X168917Y243403D01*
X160603D01*
X157200Y240000D01*
G01X228800Y305500D02*
X224235Y300935D01*
X220795D01*
X216660Y296800D01*
X207399D01*
X198209Y287610D01*
X166089D01*
Y287611D01*
X162100Y291600D01*
G01X165500Y386000D02*
X176400Y375100D01*
X191250D01*
X191940Y375790D01*
X218290D01*
X219800Y377300D01*
X233600D01*
G01X197600Y415400D02*
X196100Y416900D01*
X190676D01*
X187541Y420035D01*
X181759D01*
X178594Y416870D01*
X160582D01*
X160540Y416912D01*
G01X174600Y114000D02*
Y115960D01*
X178291Y119651D01*
X191737D01*
X194960Y116428D01*
Y110794D01*
X208622Y97132D01*
X214756D01*
X216766Y95122D01*
X234198D01*
X235515Y93805D01*
X241216D01*
X242551Y92470D01*
X246415D01*
X250279Y88606D01*
X254403D01*
X257765Y91968D01*
X262859D01*
X263102Y91725D01*
G01X176550Y125210D02*
X182570D01*
X184912Y127552D01*
X188262D01*
X189200Y128490D01*
Y130640D01*
X194460Y135900D01*
X213680D01*
X215170Y134410D01*
Y126900D01*
X213250Y124980D01*
X211780D01*
X206435Y119635D01*
Y107013D01*
X210217Y103231D01*
X233575D01*
X234233Y102573D01*
X239273D01*
X245310Y108610D01*
Y113910D01*
G01X168392Y298493D02*
X174976D01*
X178464Y301981D01*
X179184Y302279D01*
X180335Y302755D01*
X187855D01*
X188800Y303700D01*
X199342D01*
X202277Y306635D01*
X209564D01*
X212675Y303524D01*
Y303006D01*
X213481Y302200D01*
X215100D01*
X227500Y314600D01*
X235767D01*
X236787Y313580D01*
X243020D01*
X245900Y310700D01*
X255955D01*
X258255Y308400D01*
X263100D01*
X264900Y310200D01*
X279900D01*
X281300Y308800D01*
G01X216384Y312216D02*
X216366D01*
Y312198D01*
X208912D01*
X200770Y320340D01*
X195056D01*
X190592Y315876D01*
X182202D01*
X177243Y310917D01*
X176563D01*
G01X195983Y129294D02*
X196600Y127804D01*
Y115136D01*
X202745Y108991D01*
Y105483D01*
X208844Y99384D01*
X214928D01*
X217874Y96438D01*
X234972D01*
X236375Y95035D01*
X242135D01*
X242863Y94307D01*
X248477D01*
X249735Y95565D01*
X267465D01*
X273430Y101530D01*
Y103810D01*
X274760Y105140D01*
G01X219900Y267100D02*
Y267200D01*
X217500Y269600D01*
X213800D01*
X210160Y273240D01*
X199940D01*
X195834Y269134D01*
X193394D01*
X193386Y269142D01*
G01X190465Y344426D02*
X190891Y344852D01*
X202208D01*
X211556Y354200D01*
X223301D01*
X227001Y350500D01*
X275469D01*
X277500Y348469D01*
G01X221000Y343800D02*
X205200D01*
X200600Y339200D01*
X193210D01*
X192309Y340101D01*
X187398D01*
X185283Y342216D01*
X182700D01*
G01X191420Y354710D02*
X192565Y353565D01*
X205165D01*
X209700Y358100D01*
X209760D01*
X211090Y359430D01*
X226090D01*
X229590Y362930D01*
X235110D01*
X238480Y359560D01*
X260170D01*
X267065Y366455D01*
X276145D01*
G01X345500Y342690D02*
X344910Y343280D01*
Y344890D01*
X336600Y353200D01*
X333316D01*
X333305Y353189D01*
X321611D01*
X320400Y354400D01*
X303921D01*
X296771Y361550D01*
X286720D01*
X284070Y364200D01*
X271000D01*
X265130Y358330D01*
X237970D01*
X234600Y361700D01*
X230100D01*
X226600Y358200D01*
X211600D01*
X205735Y352335D01*
X195571D01*
X191326Y348090D01*
X190965D01*
G01X195300Y432327D02*
X196696Y435696D01*
X197565Y436565D01*
X203143D01*
X203983Y436217D01*
X209300Y430900D01*
X225300D01*
X229250Y434850D01*
Y435950D01*
X229900Y436600D01*
G01X185000Y454000D02*
X186400D01*
X192000Y459600D01*
X210400D01*
X214250Y455750D01*
X230010D01*
X233890Y459630D01*
X246010D01*
X246540Y459100D01*
X246800D01*
X250166Y455734D01*
Y447021D01*
X255722Y441465D01*
X262365D01*
X265855Y444955D01*
X276946D01*
X285600Y436301D01*
Y410800D01*
X292700Y403700D01*
G01X191780Y453300D02*
X193900D01*
X198200Y457600D01*
X203900D01*
X207000Y454500D01*
X230500D01*
X234400Y458400D01*
X245500D01*
X248900Y455000D01*
Y446318D01*
X255518Y439700D01*
X261700D01*
G01X297466Y51521D02*
X295796Y49851D01*
X258486D01*
X257100Y48465D01*
X246287D01*
X245178Y49574D01*
X213232D01*
X209142Y53664D01*
G01X274200Y109500D02*
X271800Y107100D01*
Y101800D01*
X266795Y96795D01*
X249225D01*
X247967Y95537D01*
X243400D01*
X242620Y96317D01*
X236833D01*
X235395Y97755D01*
X218360D01*
X215483Y100632D01*
X209336D01*
X203975Y105993D01*
Y109501D01*
X198100Y115376D01*
Y123761D01*
X200000Y125661D01*
Y128764D01*
G01X244208Y97302D02*
X243948Y97562D01*
X237328D01*
X235818Y99072D01*
X218925D01*
X216048Y101949D01*
X209759D01*
X205205Y106503D01*
Y112865D01*
X201800Y116270D01*
Y120690D01*
X202630Y121520D01*
X206580D01*
X210600Y125540D01*
Y131140D01*
X211614Y132154D01*
X212727D01*
G01X226500Y273000D02*
X224600Y271100D01*
Y264700D01*
X225100Y264200D01*
Y256500D01*
X225700Y255900D01*
Y249600D01*
X223500Y247400D01*
Y244000D01*
X224200Y243300D01*
Y234600D01*
X220200Y230600D01*
X218400D01*
X215900Y228100D01*
Y226500D01*
X213800Y224400D01*
X212400D01*
X211400Y223400D01*
Y172600D01*
X210200Y171400D01*
X206800D01*
X205200Y169800D01*
Y167539D01*
X206692Y166047D01*
G01X199729Y314565D02*
Y310771D01*
X200960Y309540D01*
X210359D01*
X212907Y306992D01*
X216092D01*
X226160Y317060D01*
X235060D01*
X237175Y319175D01*
X243885D01*
X244928Y318132D01*
Y315158D01*
X246681Y313405D01*
X250745D01*
X253157Y315817D01*
X264265D01*
G01X230445Y325945D02*
X229677D01*
X227501Y328121D01*
X200979D01*
X200300Y328800D01*
G01X208000Y373240D02*
X209430Y371810D01*
X217210D01*
X220265Y374865D01*
X232935D01*
X233300Y374500D01*
X235500D01*
X242100Y367900D01*
X259560D01*
X269630Y377970D01*
X278749D01*
X281659Y375060D01*
X288640D01*
X304035Y359665D01*
X321214D01*
X324520Y362971D01*
X330946D01*
X335475Y367500D01*
G01X197660Y390870D02*
X216750D01*
X220950Y395070D01*
X233410D01*
X235480Y397140D01*
X240759D01*
X248800Y389099D01*
Y385700D01*
G01X202513Y434800D02*
Y421986D01*
X203629Y420870D01*
X207517D01*
X208229Y421582D01*
Y428688D01*
X208941Y429400D01*
X209947D01*
X210659Y428688D01*
Y421562D01*
X211371Y420850D01*
X212377D01*
X213089Y421562D01*
Y428688D01*
X213801Y429400D01*
X214807D01*
X215519Y428688D01*
Y426812D01*
X216231Y426100D01*
X221100D01*
X222930Y424270D01*
Y418570D01*
X231200Y410300D01*
X249400D01*
G01X199000Y444500D02*
X199865Y443635D01*
X206276D01*
X207913Y444313D01*
X208734Y445134D01*
X211513Y446285D01*
X218817D01*
X220428Y444674D01*
X228007Y441535D01*
X236400D01*
X236900Y441035D01*
Y440565D01*
G01X205200Y445400D02*
Y447800D01*
X206440Y449040D01*
X218083D01*
X221605Y445518D01*
X228252Y442765D01*
X239336D01*
X240891Y441210D01*
X246591D01*
X252701Y435100D01*
X257810D01*
G01X224000Y74275D02*
Y74300D01*
X235622Y62678D01*
X242200D01*
X243233Y63711D01*
Y65983D01*
X245550Y68300D01*
X259300D01*
X270935Y79935D01*
X294032D01*
X298000Y83903D01*
Y86391D01*
X302209Y90600D01*
X312099D01*
X316050Y94551D01*
Y105894D01*
X317831Y107675D01*
Y111648D01*
X320765Y114582D01*
G01X222440Y222703D02*
X223937Y224200D01*
X226200D01*
X227274Y225274D01*
Y226774D01*
X228037Y227537D01*
X229737D01*
X230386Y228186D01*
Y229609D01*
X231244Y230467D01*
X232667D01*
X233700Y231500D01*
Y233089D01*
X237232Y241617D01*
X240540Y246566D01*
X250038Y258138D01*
X251688Y259788D01*
X252683Y260200D01*
X254200D01*
X254400Y260000D01*
X255700D01*
G01X276400Y370400D02*
X275550Y369550D01*
X266539D01*
X259109Y362120D01*
X239541D01*
X235516Y366145D01*
X232209D01*
X229950Y367080D01*
X223420D01*
G01X273100Y381500D02*
X259186D01*
X258526Y380840D01*
Y378370D01*
X257866Y377710D01*
X256856D01*
X256196Y378370D01*
Y380840D01*
X255536Y381500D01*
X254320D01*
X251420Y378600D01*
X242500D01*
X241000Y380100D01*
Y381800D01*
X235840Y386960D01*
X232950D01*
X232430Y386440D01*
X223585D01*
X222575Y387451D01*
Y387625D01*
G01X219250Y422150D02*
X221400Y420000D01*
Y417936D01*
X234913Y404423D01*
X271117D01*
X273990Y401550D01*
X289934D01*
X298152Y393332D01*
G01X308152Y172936D02*
Y171887D01*
X306717Y170452D01*
G03X306493Y169912I539J-540D01*
G01Y158202D01*
G02X305850Y156650I-2195J0D01*
G01X305269Y156069D01*
G02X303478Y155327I-1791J1791D01*
G01X263153D01*
G03X262766Y155264I-1J-1211D01*
G02X262379Y155200I-388J1147D01*
G01X253871D01*
X251468Y154914D01*
X244784D01*
X243708Y155011D01*
G02X243433Y155194I308J761D01*
G01X239857Y158770D01*
G02X239635Y159306I536J536D01*
G01Y172468D01*
G02X241141Y173974I1506J0D01*
G01X241576D01*
G03X242452Y174228I1J1635D01*
G01X244450Y175496D01*
G01X289254Y182385D02*
X287959D01*
G03X287603Y182029I0J-356D01*
G01Y181488D01*
G02X287366Y181038I-546J0D01*
G02X286452Y180757I-913J1341D01*
G01X285538D01*
G02X284424Y181493I0J1211D01*
G03X283808Y182124I-1114J-471D01*
G03X283445Y182201I-360J-804D01*
G01X279793D01*
G03X279487Y182074I0J-433D01*
G01X273877Y176464D01*
G02X273257Y176116I-929J930D01*
G01X273045Y176066D01*
G03X272158Y175569I439J-1823D01*
G01X271397Y174808D01*
G02X270981Y174636I-416J416D01*
G01X262150D01*
G02X261389Y175397I0J761D01*
G01Y176707D01*
G03X259408Y178688I-1981J0D01*
G01X256879D01*
G02X255570Y179230I0J1852D01*
G01X254942Y179858D01*
G03X253633Y180400I-1309J-1310D01*
G01X252900D01*
G02X252400Y180900I0J500D01*
G01Y185800D01*
G03X251709Y186491I-691J0D01*
G01X249563D01*
G02X249223Y186831I0J340D01*
G01Y191931D01*
G03X248318Y192836I-905J0D01*
G01X246670D01*
G03X246072Y192238I0J-598D01*
G01Y186941D01*
G02X245732Y186601I-340J0D01*
G01X243480D01*
G02X242800Y187281I0J680D01*
G01Y192311D01*
G03X242287Y192824I-513J0D01*
G01X239984D01*
G03X239644Y192484I0J-340D01*
G01Y191486D01*
G02X239304Y191146I-340J0D01*
G01X237381D01*
G03X237041Y190806I0J-340D01*
G01Y189346D01*
G03X237381Y189006I340J0D01*
G01X239304D01*
G02X239644Y188666I0J-340D01*
G01Y187206D01*
G02X239304Y186866I-340J0D01*
G01X237450D01*
G03X237110Y186526I0J-340D01*
G01Y185066D01*
G03X237450Y184726I340J0D01*
G01X239304D01*
G02X239644Y184386I0J-340D01*
G01Y181852D01*
G03X240396Y181100I752J0D01*
G01X241740D01*
G03X242181Y181541I0J441D01*
G01Y183009D01*
G02X242571Y183399I390J0D01*
G01X244110D01*
G03X244450Y183739I0J340D01*
G01Y184945D01*
G01X247599Y210104D02*
X245680D01*
G02X245340Y210444I0J340D01*
G01Y211321D01*
G03X245000Y211661I-340J0D01*
G01X240166D01*
G03X239826Y211321I0J-340D01*
G01Y209064D01*
G02X239334Y208572I-492J0D01*
G01X236908D01*
G03X236568Y208232I0J-340D01*
G01Y203823D01*
G03X236908Y203483I340J0D01*
G01X239472D01*
G02X239812Y203143I0J-340D01*
G01Y196423D01*
G02X239472Y196083I-340J0D01*
G01X238541D01*
G02X238201Y196423I0J340D01*
G01Y199995D01*
G03X237861Y200335I-340J0D01*
G01X236837D01*
G03X236497Y199995I0J-340D01*
G01Y194912D01*
G03X237012Y194397I515J0D01*
G01X247972D01*
G02X249270Y193859I0J-1835D01*
G01X249858Y193271D01*
G03X250244Y193111I386J386D01*
G01X258125D01*
G03X259831Y193818I0J2412D01*
G01X260252Y194239D01*
G02X261518Y194763I1266J-1267D01*
G01X280278D01*
G03X282746Y195254I0J6446D01*
G01X284440Y195956D01*
G02X286670Y196399I2229J-5384D01*
G01X289776D01*
G03X290715Y196943I0J1082D01*
G01X290757Y197017D01*
G03X290852Y197375I-625J358D01*
G01Y199166D01*
G02X291192Y199506I340J0D01*
G01X292064D01*
G03X292404Y199846I0J340D01*
G01Y201282D01*
G01X244450Y200655D02*
X245619D01*
G03X245959Y200995I0J340D01*
G01Y207154D01*
G03X245619Y207494I-340J0D01*
G01X244927D01*
G02X244587Y207834I0J340D01*
G01Y209007D01*
G03X244247Y209347I-340J0D01*
G01X242922D01*
G03X242582Y209007I0J-340D01*
G01Y207834D01*
G02X242242Y207494I-340J0D01*
G01X238875D01*
G03X238535Y207154I0J-340D01*
G01Y205651D01*
G03X238875Y205311I340J0D01*
G01X242592D01*
G02X242932Y204971I0J-340D01*
G01Y195796D01*
G03X243272Y195456I340J0D01*
G01X245619D01*
G03X245959Y195796I0J340D01*
G01Y198722D01*
G02X246299Y199062I340J0D01*
G01X248614D01*
G02X249192Y198484I0J-578D01*
G01Y196181D01*
G03X250470Y194456I1803J0D01*
G03X250807Y194406I336J1106D01*
G01X251738D01*
G03X252078Y194746I0J340D01*
G01Y195665D01*
G02X252418Y196005I340J0D01*
G01X253578D01*
G02X253918Y195665I0J-340D01*
G01Y194380D01*
G03X254258Y194040I340J0D01*
G01X255419D01*
G03X255759Y194380I0J340D01*
G01Y195679D01*
G02X256099Y196019I340J0D01*
G01X257375D01*
G02X257715Y195679I0J-340D01*
G01Y194713D01*
G03X258055Y194373I340J0D01*
G01X259168D01*
G03X259508Y194713I0J340D01*
G01Y195813D01*
G02X259848Y196153I340J0D01*
G01X278065D01*
G03X278405Y196493I0J340D01*
G01Y199730D01*
G02X278745Y200070I340J0D01*
G01X280390D01*
G02X280730Y199730I0J-340D01*
G01Y197337D01*
G03X281070Y196997I340J0D01*
G01X283301D01*
G03X283641Y197337I0J340D01*
G01Y199156D01*
G02X283981Y199496I340J0D01*
G01X288914D01*
G03X289254Y199836I0J340D01*
G01Y201139D01*
G01X258628Y247600D02*
X239465Y239664D01*
X238066Y238265D01*
X237080Y235884D01*
Y229038D01*
X237073Y228995D01*
X235455Y227377D01*
X234446D01*
X233490Y226421D01*
Y225412D01*
X232467Y224389D01*
X231398D01*
X229737Y223701D01*
X228739Y222703D01*
G01X252639Y247885D02*
X250785D01*
X248247Y245347D01*
X237990Y241099D01*
X235340Y234699D01*
Y231441D01*
X233333Y229434D01*
Y228405D01*
X232406Y227478D01*
X231398D01*
X230332Y226412D01*
Y225332D01*
X229300Y224300D01*
X228000D01*
X227200Y223500D01*
Y217980D01*
X228739Y216441D01*
G01X227232Y270539D02*
X231393Y274700D01*
X243069D01*
X245100Y272669D01*
Y268399D01*
X248699Y264800D01*
X253865D01*
X258625Y269560D01*
X265740D01*
X266600Y268700D01*
G01X295075Y119100D02*
X298400Y122425D01*
Y129804D01*
X300496Y131900D01*
X304640D01*
X310984Y138244D01*
X322219D01*
X328428Y144453D01*
X340923D01*
X342520Y146050D01*
Y306170D01*
X331831Y316859D01*
Y335859D01*
X325170Y342520D01*
X315570D01*
X313070Y345020D01*
X291796D01*
X286556Y339780D01*
X273380D01*
X265890Y332290D01*
X254594D01*
X242973Y343911D01*
X233500D01*
G01X233650Y359628D02*
X236178Y357100D01*
X270650D01*
X275310Y361760D01*
X283210D01*
X285670Y359300D01*
X295820D01*
X303260Y351860D01*
X316240D01*
X319000Y349100D01*
X327900D01*
X338341Y338659D01*
Y319659D01*
X349100Y308900D01*
Y134400D01*
X337400Y122700D01*
X327600D01*
X325853Y124447D01*
X320204D01*
X316275Y120518D01*
Y117575D01*
X315100Y116400D01*
G01X298575Y101900D02*
X302000D01*
X312800Y112700D01*
Y118373D01*
X319814Y125387D01*
X326243D01*
X327990Y123640D01*
X337010D01*
X348160Y134790D01*
Y308510D01*
X337411Y319259D01*
Y338259D01*
X327510Y348160D01*
X318210D01*
X315450Y350920D01*
X302770D01*
X295380Y358310D01*
X285270D01*
X282820Y360760D01*
X275650D01*
X270893Y356003D01*
X261603D01*
X259900Y354300D01*
X233800D01*
G01X300500Y125000D02*
X311864Y136364D01*
X330031D01*
X331400Y134995D01*
X338995D01*
X344400Y140400D01*
Y306950D01*
X333691Y317659D01*
Y336659D01*
X325950Y344400D01*
X316350D01*
X313850Y346900D01*
X291016D01*
X285756Y341640D01*
X266656D01*
X261476Y336460D01*
X260060D01*
X257700Y334100D01*
X254100D01*
X241289Y346911D01*
X233500D01*
G01X250749Y169197D02*
X251892D01*
G02X252232Y168857I0J-340D01*
G01Y164845D01*
G03X252572Y164505I340J0D01*
G01X255193D01*
G02X256068Y163630I0J-875D01*
G01Y162305D01*
G03X257216Y161157I1148J0D01*
G01X280346D01*
G03X281144Y161955I0J798D01*
G01Y166213D01*
G02X281514Y166583I370J0D01*
G01X282989D01*
G02X283359Y166213I0J-370D01*
G01Y161558D01*
G03X283729Y161188I370J0D01*
G01X287220D01*
G03X287590Y161558I0J370D01*
G01Y164676D01*
G02X287930Y165016I340J0D01*
G01X289260D01*
G02X290614Y163662I0J-1354D01*
G01Y161694D01*
G03X290985Y161323I371J0D01*
G01X293128D01*
G03X294545Y162740I0J1417D01*
G01Y164708D01*
G03X294175Y165078I-370J0D01*
G01X291677D01*
G02X291300Y165455I0J377D01*
G01Y167779D01*
G02X291670Y168149I370J0D01*
G01X294918D01*
G02X295288Y167779I0J-370D01*
G01Y166629D01*
G03X295658Y166259I370J0D01*
G01X299354D01*
G03X300019Y166924I0J665D01*
G01Y169121D01*
G03X299354Y169786I-665J0D01*
G01X298273D01*
G02X297610Y170449I0J663D01*
G01Y170915D01*
G03X297106Y171419I-504J0D01*
G01X295948D01*
G03X295410Y170881I0J-538D01*
G01Y169786D01*
G01X305002Y176085D02*
Y175045D01*
X303230Y173273D01*
G02X302967Y173164I-263J263D01*
G01X298983D01*
G03X298643Y172824I0J-340D01*
G01Y171435D01*
G03X298983Y171095I340J0D01*
G01X300946D01*
G02X301700Y170341I0J-754D01*
G01Y166581D01*
G02X299989Y164870I-1711J0D01*
G01X296477D01*
G03X296137Y164530I0J-340D01*
G01Y163226D01*
G02X292678Y159767I-3459J0D01*
G01X256170D01*
G02X255297Y160600I0J874D01*
G01Y160606D01*
G03X254556Y161311I-741J-37D01*
G01X250180D01*
G02X249203Y162288I0J977D01*
G01Y172596D01*
G02X250569Y173962I1366J0D01*
G01X251232D01*
G03X252400Y175130I0J1168D01*
G01Y176638D01*
G03X251883Y177155I-517J0D01*
G01X249548D01*
G02X249097Y177606I0J451D01*
G01Y182913D01*
G03X248757Y183253I-340J0D01*
G01X248012D01*
G02X247599Y183666I0J413D01*
G01Y184945D01*
G01X305002Y169786D02*
Y158362D01*
G02X304683Y157592I-1089J0D01*
G01X304329Y157238D01*
G02X303316Y156818I-1013J1012D01*
G01X293643D01*
X293614Y156847D01*
X247714D01*
G02X245916Y157495I0J2819D01*
G03X244276Y158138I-1798J-2172D01*
G02X242910Y159509I106J1472D01*
G01Y172457D01*
G02X243229Y173227I1089J0D01*
G01X243904Y173902D01*
G02X244167Y174011I263J-263D01*
G01X244912D01*
G03X245175Y174120I0J372D01*
G01X245794Y174739D01*
G03X246094Y175463I-724J724D01*
G01Y176643D01*
G03X245724Y177013I-370J0D01*
G01X243335D01*
G02X242935Y177413I0J400D01*
G01Y179776D01*
G02X243305Y180146I370J0D01*
G01X244069D01*
G03X244453Y180530I0J384D01*
G01Y181792D01*
X244450Y181795D01*
G01X250749Y175496D02*
X249462D01*
G03X249092Y175126I0J-370D01*
G01Y174873D01*
G02X248105Y173886I-987J0D01*
G01X247327D01*
G03X246114Y172673I0J-1213D01*
G01Y159792D01*
G03X247706Y158200I1592J0D01*
G01X257485D01*
G03X257829Y158287I1J720D01*
G02X258169Y158373I339J-626D01*
G01X295661D01*
G03X295895Y158470I0J331D01*
G01X296850Y159425D01*
G02X297318I234J-234D01*
G01X298338Y158405D01*
G03X298806I234J234D01*
G01X299915Y159514D01*
G03Y159982I-234J234D01*
G01X298899Y160998D01*
G02Y161474I238J238D01*
G01X300004Y162579D01*
G02X300472I234J-234D01*
G01X301492Y161559D01*
G03X301960I234J234D01*
G01X303069Y162668D01*
G03Y163136I-234J234D01*
G01X302049Y164156D01*
G02Y164624I234J234D01*
G01X303116Y165691D01*
G03X303213Y165925I-234J234D01*
G01Y170953D01*
G02X303553Y171293I340J0D01*
G01X305979D01*
G03X306349Y171663I0J370D01*
G01Y172596D01*
G03X306009Y172936I-340J0D01*
G01X305002D01*
G01X292404Y176085D02*
Y174920D01*
G03X292889Y174435I485J0D01*
G01X293551D01*
G02X293891Y174095I0J-340D01*
G01Y171745D01*
G02X293453Y171307I-438J0D01*
G01X290666D01*
G03X289800Y170441I0J-866D01*
G01Y166570D01*
G02X289430Y166200I-370J0D01*
G01X287470D01*
G02X287100Y166570I0J370D01*
G01Y169044D01*
G03X286482Y169662I-618J0D01*
G01X284307D01*
G03X283937Y169292I0J-370D01*
G01Y168595D01*
G02X283447Y168105I-490J0D01*
G01X280339D01*
G03X280014Y167989I-1J-509D01*
G03X279639Y167190I661J-798D01*
G01Y162924D01*
G02X279299Y162584I-340J0D01*
G01X277851D01*
G02X277481Y162954I0J370D01*
G01Y166100D01*
G03X277141Y166440I-340J0D01*
G01X275666D01*
G03X275326Y166100I0J-340D01*
G01Y163071D01*
G02X274796Y162541I-530J0D01*
G01X273477D01*
G02X273107Y162911I0J370D01*
G01Y165608D01*
G03X272505Y166210I-602J0D01*
G01X271529D01*
G03X270927Y165608I0J-602D01*
G01Y162932D01*
G02X270557Y162562I-370J0D01*
G01X267541D01*
G02X267192Y162682I0J568D01*
G02X267049Y162975I229J293D01*
G01Y166278D01*
G03X266557Y166770I-492J0D01*
G01X263864D01*
G03X263441Y166347I0J-423D01*
G01Y163030D01*
G02X263111Y162700I-330J0D01*
G01X258312D01*
G02X257982Y163030I0J330D01*
G01Y164403D01*
G02X258312Y164733I330J0D01*
G01X259170D01*
G03X259500Y165063I0J330D01*
G01Y166633D01*
G03X259170Y166963I-330J0D01*
G01X258312D01*
G02X257982Y167293I0J330D01*
G01Y170460D01*
G03X257642Y170800I-340J0D01*
G01X256116D01*
G03X255607Y170291I0J-509D01*
G01Y167830D01*
G02X255277Y167500I-330J0D01*
G01X254228D01*
G02X253898Y167830I0J330D01*
G01Y169197D01*
G01X289254Y176085D02*
X290507D01*
G02X290877Y175715I0J-370D01*
G01Y174729D01*
G02X290507Y174359I-370J0D01*
G01X288134D01*
G03X287764Y173989I0J-370D01*
G01Y171218D01*
G02X287183Y170637I-581J0D01*
G01X285163D01*
G02X284614Y171186I0J549D01*
G01Y175887D01*
G03X284244Y176257I-370J0D01*
G01X281757D01*
G03X281387Y175887I0J-370D01*
G01Y172954D01*
G03X281791Y171979I1379J0D01*
G01X282144Y171626D01*
G02X282497Y170774I-852J-852D01*
G01Y170174D01*
G02X281794Y169471I-703J0D01*
G01X279910D01*
G03X279222Y169186I0J-973D01*
G01X278767Y168731D01*
G02X278342Y168555I-425J425D01*
G01X278027D01*
G02X277627Y168955I0J400D01*
G01Y170582D01*
G03X277108Y171101I-519J0D01*
G01X275973D01*
G03X275454Y170582I0J-519D01*
G01Y168070D01*
G02X275084Y167700I-370J0D01*
G01X272951D01*
G02X272581Y168070I0J370D01*
G01Y170993D01*
G03X272211Y171363I-370J0D01*
G01X270757D01*
G03X270387Y170993I0J-370D01*
G01Y167477D01*
G02X270017Y167107I-370J0D01*
G01X268583D01*
G02X268213Y167477I0J370D01*
G01Y171502D01*
G03X267843Y171872I-370J0D01*
G01X266409D01*
G03X266039Y171502I0J-370D01*
G01Y168537D01*
G02X265669Y168167I-370J0D01*
G01X264239D01*
G02X263869Y168537I0J370D01*
G01Y171502D01*
G03X263499Y171872I-370J0D01*
G01X262048D01*
G03X261678Y171502I0J-370D01*
G01Y168415D01*
G02X261338Y168075I-340J0D01*
G01X260168D01*
G02X259798Y168445I0J370D01*
G01Y173410D01*
G03X259458Y173750I-340J0D01*
G01X257951D01*
G02X257581Y174120I0J370D01*
G01Y175418D01*
G03X257211Y175788I-370J0D01*
G01X255863D01*
G03X255493Y175418I0J-370D01*
G01Y174208D01*
G02X255123Y173838I-370J0D01*
G01X253070D01*
G03X252387Y173155I0J-683D01*
G01X252376D01*
Y171188D01*
G02X251793Y170605I-583J0D01*
G01X251332D01*
G02X250749Y171188I0J583D01*
G01Y172347D01*
G01X253898Y175496D02*
Y176626D01*
G02X254486Y177214I588J0D01*
G01X259500D01*
G02X259870Y176844I0J-370D01*
G01Y175397D01*
G03X260481Y173922I2086J0D01*
G01X260804Y173599D01*
G03X261130Y173342I1239J1236D01*
G03X261487Y173242I356J584D01*
G01X271568D01*
G02X272780Y172739I0J-1713D01*
G03X273140Y172506I719J716D01*
G01X277764D01*
G03X278104Y172846I0J340D01*
G01Y173603D01*
G02X278617Y174116I513J0D01*
G01X279613D01*
G03X279953Y174456I0J340D01*
G01Y176688D01*
G02X280457Y177542I974J1D01*
G02X280787Y177626I328J-600D01*
G01X294960D01*
G02X295300Y177286I0J-340D01*
G01Y175013D01*
G03X295813Y174500I513J0D01*
G01X297216D01*
G03X297546Y174830I0J330D01*
G01Y174970D01*
G02X297876Y175300I330J0D01*
G01X299446D01*
G02X299776Y174970I0J-330D01*
G01Y174830D01*
G03X300106Y174500I330J0D01*
G01X303060D01*
G03X303400Y174840I0J340D01*
G01Y177074D01*
G02X303952Y177626I552J0D01*
G01X306149D01*
G02X306519Y177256I0J-370D01*
G01Y174838D01*
G03X306859Y174498I340J0D01*
G01X311856D01*
G03X312196Y174838I0J340D01*
G01Y176279D01*
G03X311856Y176619I-340J0D01*
G01X309787D01*
G02X309417Y176989I0J370D01*
G01Y178270D01*
G02X309787Y178640I370J0D01*
G01X311822D01*
G03X312162Y178980I0J340D01*
G01Y180547D01*
G03X311822Y180887I-340J0D01*
G01X305370D01*
G03X305000Y180517I0J-370D01*
G01Y179235D01*
X305002D01*
G01X308008Y207438D02*
X310235D01*
G03X311011Y208214I0J776D01*
G01Y208288D01*
G03X310235Y209064I-776J0D01*
G01X305683D01*
G03X304573Y207954I0J-1110D01*
G01Y207741D01*
G02X303603Y206771I-970J0D01*
G01X303492D01*
G02X302559Y207704I0J933D01*
G01Y207778D01*
G03X301626Y208711I-933J0D01*
G01X301415D01*
G03X300539Y207835I0J-876D01*
G01Y207762D01*
G02X299663Y206886I-876J0D01*
G01X298765D01*
G02X297695Y207956I0J1070D01*
G01Y208126D01*
G03X296722Y209099I-973J0D01*
G01X296515D01*
G03X295675Y208259I0J-840D01*
G01Y208186D01*
G02X294835Y207346I-840J0D01*
G01X294652D01*
G02X293805Y208193I0J847D01*
G01X293900Y208288D01*
Y211684D01*
X293486Y212098D01*
X285774D01*
G02X284627Y212573I0J1622D01*
G01X284575Y212625D01*
G03X283428Y213100I-1147J-1147D01*
G01X282274D01*
G03X281904Y212730I0J-370D01*
G01Y210657D01*
G02X281443Y210196I-461J0D01*
G01X279904D01*
G02X279534Y210566I0J370D01*
G01Y212730D01*
G03X279164Y213100I-370J0D01*
G01X278190D01*
G03X276761Y212508I0J-2021D01*
G01X276379Y212126D01*
G03Y211602I262J-262D01*
G01X277229Y210752D01*
G02Y210228I-261J-262D01*
G01X276077Y209076D01*
G02X275553I-262J261D01*
G01X274703Y209926D01*
G03X274179I-262J-262D01*
G01X273784Y209531D01*
G03X273242Y208222I1310J-1309D01*
G01Y207858D01*
G02X272184Y206800I-1058J0D01*
G01X272070D01*
G02X270972Y207898I0J1098D01*
G01Y208307D01*
G03X269729Y209550I-1243J0D01*
G01X256269D01*
G02X254956Y210094I0J1857D01*
G01X251934Y213116D01*
G03X251601Y213254I-333J-333D01*
G01X250749D01*
G01X292404Y210587D02*
X292260Y210443D01*
Y209416D01*
G02X291920Y209076I-340J0D01*
G01X282739D01*
G03X281141Y207478I0J-1598D01*
G01Y205948D01*
G02X280801Y205608I-340J0D01*
G01X279287D01*
G02X278947Y205948I0J340D01*
G01Y207708D01*
G03X278607Y208048I-340J0D01*
G01X277096D01*
G03X276756Y207708I0J-340D01*
G01Y206040D01*
G02X276416Y205700I-340J0D01*
G01X273964D01*
G03X273723Y205600I0J-340D01*
G01X273420Y205296D01*
G02X272873Y205069I-547J545D01*
G01X261537D01*
G02X261199Y205094I1J2312D01*
G01X259328Y205371D01*
G03X258989Y205396I-339J-2288D01*
G01X256695D01*
G02X255514Y206577I0J1181D01*
G01Y207120D01*
G03X255016Y208323I-1702J0D01*
G01X252182Y211157D01*
G03X250713Y211765I-1469J-1470D01*
G01X246883D01*
G02X245998Y212650I0J885D01*
G01Y216686D01*
G02X246198Y217168I681J0D01*
G01X246559Y217529D01*
G02X247762Y218027I1203J-1204D01*
G01X258212D01*
G03X258552Y218367I0J340D01*
G01Y218545D01*
G02X258892Y218885I340J0D01*
G01X261121D01*
G02X261461Y218545I0J-340D01*
G01Y216833D01*
G02X261121Y216493I-340J0D01*
G01X260063D01*
G03X259723Y216153I0J-340D01*
G01Y215151D01*
G02X259383Y214811I-340J0D01*
G01X247939D01*
G03X247599Y214471I0J-340D01*
G01Y213254D01*
G01Y206955D02*
X247800Y206754D01*
G02X249170Y203447I-3306J-3307D01*
G01Y200412D01*
G03X250529Y199053I1359J0D01*
G01X257002D01*
G02X257370Y199005I3J-1410D01*
G02X258368Y198291I-458J-1695D01*
G03X259772Y197543I1404J944D01*
G01X276605D01*
G03X276945Y197883I0J340D01*
G01Y201148D01*
G02X277285Y201488I340J0D01*
G01X284132D01*
G03X284438Y201615I0J433D01*
G01X285468Y202645D01*
G02X285820Y202791I352J-351D01*
G01X293638D01*
G02X294008Y202421I0J-370D01*
G01Y199237D01*
G03X294527Y198718I519J0D01*
G01X296976D01*
G02X298182Y198218I-1J-1706D01*
G01X298801Y197599D01*
G03X300092Y197064I1291J1290D01*
G01X302887D01*
G03X303227Y197404I0J340D01*
G01Y199909D01*
G02X303567Y200249I340J0D01*
G01X305027D01*
G02X305367Y199909I0J-340D01*
G01Y196792D01*
G03X305707Y196452I340J0D01*
G01X315855D01*
G03X316300Y196897I0J445D01*
G01Y199072D01*
G03X315750Y199622I-550J0D01*
G01X309964D01*
G02X309624Y199962I0J340D01*
G01Y200185D01*
G03X309284Y200525I-340J0D01*
G01X307340D01*
G02X307000Y200865I0J340D01*
G01Y202325D01*
G02X307340Y202665I340J0D01*
G01X307812D01*
G03X308152Y203005I0J340D01*
G01Y204432D01*
G01X305002D02*
Y202106D01*
G02X304662Y201766I-340J0D01*
G01X303726D01*
G02X303356Y202136I0J370D01*
G01Y204534D01*
G03X302986Y204904I-370J0D01*
G01X301594D01*
G03X301224Y204534I0J-370D01*
G01Y199170D01*
G02X300854Y198800I-370J0D01*
G01X299611D01*
G02X299241Y199170I0J370D01*
G01Y199638D01*
G03X298871Y200008I-370J0D01*
G01X295836D01*
G02X295289Y200555I0J547D01*
G01Y202135D01*
G02X295659Y202505I370J0D01*
G01X298534D01*
G03X298904Y202875I0J370D01*
G01Y203866D01*
G03X298338Y204432I-566J0D01*
G01X292566D01*
G02X292192Y204587I0J529D01*
G01X291051Y205728D01*
G03X290788Y205837I-263J-263D01*
G01X285215D01*
G03X284597Y205219I0J-618D01*
G01Y204315D01*
G02X284225Y203417I-1270J0D01*
G01X284048Y203240D01*
G02X283165Y202874I-883J882D01*
G01X275463D01*
G03X275123Y202534I0J-340D01*
G01Y199301D01*
G02X274753Y198931I-370J0D01*
G01X273173D01*
G02X272803Y199301I0J370D01*
G01Y201838D01*
G03X272463Y202178I-340J0D01*
G01X270727D01*
G03X270387Y201838I0J-340D01*
G01Y199341D01*
G02X270017Y198971I-370J0D01*
G01X268450D01*
G02X268067Y199354I0J383D01*
G01Y201844D01*
G03X267697Y202214I-370J0D01*
G01X266117D01*
G03X265747Y201844I0J-370D01*
G01Y199281D01*
G02X265377Y198911I-370J0D01*
G01X263797D01*
G02X263427Y199281I0J370D01*
G01Y201844D01*
G03X263057Y202214I-370J0D01*
G01X261477D01*
G03X261107Y201844I0J-370D01*
G01Y199321D01*
G02X260737Y198951I-370J0D01*
G01X259157D01*
G02X258787Y199321I0J370D01*
G01Y201844D01*
G03X258417Y202214I-370J0D01*
G01X252662D01*
G02X252292Y202584I0J370D01*
G01Y204218D01*
G03X252183Y204481I-372J0D01*
G01X250858Y205806D01*
G02X250749Y206069I263J263D01*
G01Y206955D01*
G01X292404Y213737D02*
X292384D01*
X291303Y214818D01*
G03X291038Y215030I-1072J-1069D01*
G03X289935Y215347I-1102J-1757D01*
G01X277627D01*
G03X276297Y214796I0J-1881D01*
G01X273542Y212041D01*
G02X270889Y210942I-2653J2653D01*
G01X257455D01*
G02X257078Y211098I0J533D01*
G01X255031Y213145D01*
G03X254768Y213254I-263J-263D01*
G01X253898D01*
G01X250749Y210104D02*
X249503D01*
G03X249163Y209764I0J-340D01*
G01Y208826D01*
G03X249533Y208456I370J0D01*
G01X251902D01*
G02X252272Y208086I0J-370D01*
G01Y206599D01*
G03X252402Y206286I442J0D01*
G01X253336Y205352D01*
G02X253445Y205089I-263J-263D01*
G01Y204205D01*
G03X253815Y203835I370J0D01*
G01X258956D01*
G02X259646Y203707I2J-1911D01*
G03X260335Y203578I690J1782D01*
G01X273764D01*
G03X274143Y203735I1J534D01*
G01X274546Y204139D01*
G02X274788Y204239I241J-242D01*
G01X282602D01*
G03X282968Y204605I0J366D01*
G01Y206579D01*
G02X283834Y207445I866J0D01*
G01X291639D01*
G02X291902Y207336I0J-372D01*
G01X293219Y206019D01*
G03X294130Y205642I911J912D01*
G01X295689D01*
G03X296291Y205775I-1J1435D01*
G02X297072Y205947I780J-1684D01*
G01X309293D01*
G02X309663Y205577I0J-370D01*
G01Y203080D01*
G03X310033Y202710I370J0D01*
G01X316150D01*
G03X316581Y203141I0J431D01*
G01Y205449D01*
G03X316241Y205789I-340J0D01*
G01X312686D01*
G02X312346Y206129I0J340D01*
G01Y208764D01*
G02X312686Y209104I340J0D01*
G01X316224D01*
G03X316696Y209576I0J472D01*
G01Y211760D01*
G03X316356Y212100I-340J0D01*
G01X311652D01*
G03X311158Y211606I0J-494D01*
G01Y210587D01*
G01X301000Y121016D02*
X302884D01*
X303370Y120530D01*
X308134D01*
X309766Y122162D01*
Y124100D01*
X318420Y132754D01*
X338554D01*
X345340Y139540D01*
Y307340D01*
X334621Y318059D01*
Y337059D01*
X326340Y345340D01*
X316740D01*
X314240Y347840D01*
X290626D01*
X285356Y342570D01*
X266270D01*
X262460Y338760D01*
X258529D01*
X256124Y336355D01*
G01X283973Y382553D02*
X285870Y380656D01*
Y378380D01*
X284500Y377010D01*
X281590D01*
X279300Y379300D01*
X266167D01*
X257982Y375910D01*
X244790D01*
G01X287578Y84092D02*
X287608D01*
X287430Y84270D01*
Y109471D01*
X280201Y116700D01*
X270000D01*
X266470Y120230D01*
Y124980D01*
X265530Y125920D01*
X263070D01*
X262151Y125001D01*
X260388D01*
G01X295411Y185534D02*
X295410Y185533D01*
Y184286D01*
G02X295070Y183946I-340J0D01*
G01X293643D01*
G03X292984Y183673I0J-932D01*
G01X292248Y182937D01*
G02X291730Y182722I-519J518D01*
G01X291362D01*
G02X290925Y182903I0J618D01*
G01X290112Y183716D01*
G03X289557Y183946I-555J-555D01*
G01X285903D01*
G03X285407Y183740I1J-702D01*
G01X285383Y183716D01*
G02X285110Y183603I-273J273D01*
G01X280537D01*
G02X280303Y183700I0J331D01*
G01X280000Y184003D01*
G03X279766Y184100I-234J-234D01*
G01X278137D01*
G03X277903Y184003I0J-331D01*
G01X277180Y183280D01*
G03X277083Y183046I234J-234D01*
G01Y181754D01*
G02X276986Y181520I-331J0D01*
G01X275940Y180474D01*
G02X274817I-562J562D01*
G01X272706Y182585D01*
G03X272139I-283J-283D01*
G01X271146Y181592D01*
G03Y181021I285J-286D01*
G01X273577Y178590D01*
Y178108D01*
X273223Y177754D01*
G02X272668Y177524I-555J555D01*
G01X271209D01*
G01X270472Y188488D02*
X272440Y190456D01*
G02X273342Y190830I902J-902D01*
G01X281476D01*
G03X282530Y191040I0J2750D01*
G01X283167Y191304D01*
G02X285020Y191672I1851J-4473D01*
G01X286409D01*
G02X286672Y191563I0J-372D01*
G01X287840Y190395D01*
G03X288273Y190138I715J712D01*
G03X288611Y190091I334J1166D01*
G01X299843D01*
G03X300183Y190431I0J340D01*
G01Y191311D01*
G02X300553Y191681I370J0D01*
G01X301833D01*
G02X302203Y191311I0J-370D01*
G01Y188632D01*
G03X302543Y188292I340J0D01*
G01X303883D01*
G03X304223Y188632I0J340D01*
G01Y191295D01*
G02X304593Y191665I370J0D01*
G01X305873D01*
G02X306243Y191295I0J-370D01*
G01Y190469D01*
G03X306613Y190099I370J0D01*
G01X312028D01*
G02X312673Y189726I0J-744D01*
G02X312805Y189229I-870J-497D01*
G01Y183662D01*
G03X313105Y183324I340J-1D01*
G02X313404Y182986I-42J-338D01*
G01Y173597D01*
G02X313064Y173257I-340J0D01*
G01X310326D01*
G03X309986Y172917I0J-340D01*
G01Y171510D01*
G03X310326Y171170I340J0D01*
G01X313064D01*
G02X313404Y170830I0J-340D01*
G01Y168493D01*
G02X313064Y168153I-340J0D01*
G01X308492D01*
G02X308152Y168493I0J340D01*
G01Y169786D01*
G01X257048Y191244D02*
X258081D01*
G03X258804Y191544I-1J1023D01*
G01X259028Y191768D01*
G02X259926Y192140I898J-898D01*
G01X261204D01*
G02X262073Y191271I0J-869D01*
G01Y191270D01*
G03X262942Y190401I869J0D01*
G01X263224D01*
G03X264093Y191270I0J869D01*
G01Y191271D01*
G02X264962Y192140I869J0D01*
G01X265244D01*
G02X266113Y191271I0J-869D01*
G01Y191270D01*
G03X266982Y190401I869J0D01*
G01X267264D01*
G03X268133Y191270I0J869D01*
G01Y191531D01*
G02X268787Y192520I1075J0D01*
G02X269148Y192593I361J-856D01*
G01X281529D01*
G03X282474Y192781I0J2469D01*
G01X283136Y193055D01*
G02X283740Y193175I604J-1459D01*
G01X294989D01*
G02X295329Y192835I0J-340D01*
G01Y191687D01*
G03X295669Y191347I340J0D01*
G01X297129D01*
G03X297469Y191687I0J340D01*
G01Y192835D01*
G02X297809Y193175I340J0D01*
G01X316173D01*
G02X316513Y192835I0J-340D01*
G01Y166977D01*
G02X316173Y166637I-340J0D01*
G01X308008D01*
G01X298714Y210477D02*
Y210462D01*
X302622D01*
G03X302957Y210740I1J340D01*
G03X302972Y210910I-918J167D01*
G01Y210911D01*
G03X302099Y211784I-873J0D01*
G01X299590D01*
G02X298725Y212649I0J865D01*
G01Y212717D01*
G02X299233Y213225I508J0D01*
G01X301983D01*
G03X302734Y213976I0J751D01*
G01Y214043D01*
G03X301983Y214794I-751J0D01*
G01X297964D01*
G03X297722Y214694I0J-343D01*
G03X297378Y213864I829J-830D01*
G01Y212492D01*
G02X297278Y212251I-340J0D01*
G02X297010Y212140I-268J268D01*
G01X294832D01*
G02X294580Y212244I0J357D01*
G01X294532Y212292D01*
G02X294428Y212544I253J252D01*
G01Y217043D01*
G03X294088Y217383I-340J0D01*
G01X292535D01*
G03X292195Y217043I0J-340D01*
G01Y216658D01*
G02X291855Y216318I-340J0D01*
G01X290188D01*
G02X289848Y216658I0J340D01*
G01Y216976D01*
G03X289508Y217316I-340J0D01*
G01X276848D01*
G03X275643Y216817I0J-1704D01*
G01X274891Y216065D01*
X274411D01*
X273668Y216808D01*
X273188D01*
X272077Y215697D01*
Y215217D01*
X272820Y214474D01*
Y213994D01*
X271998Y213172D01*
G02X269901Y212303I-2097J2096D01*
G01X260926D01*
G02X260327Y212457I0J1242D01*
G01X259492Y213254D01*
X257048D01*
G01X259420Y343230D02*
X260690Y344500D01*
X284626D01*
X289846Y349720D01*
X315020D01*
X317520Y347220D01*
X327120D01*
X336481Y337859D01*
Y318859D01*
X347220Y308120D01*
Y135180D01*
X338120Y126080D01*
X336620D01*
X335100Y127600D01*
X320697D01*
X316397Y123300D01*
X314800D01*
X313800Y124300D01*
G01X259420Y340630D02*
X262290Y343500D01*
X284956D01*
X290236Y348780D01*
X314630D01*
X317130Y346280D01*
X326730D01*
X335551Y337459D01*
Y318459D01*
X346280Y307730D01*
Y138880D01*
X339214Y131814D01*
X318810D01*
X312030Y125034D01*
Y122630D01*
X308300Y118900D01*
X298975D01*
G01X261300Y334100D02*
X267910Y340710D01*
X286156D01*
X291406Y345960D01*
X313460D01*
X315960Y343460D01*
X325560D01*
X332761Y336259D01*
Y317259D01*
X343460Y306560D01*
Y145660D01*
X341313Y143513D01*
X330907D01*
X329871Y142477D01*
Y140888D01*
X326287Y137304D01*
X311374D01*
X303970Y129900D01*
X301000D01*
G01X265100Y395100D02*
X269970Y390230D01*
X278670D01*
X282740Y394300D01*
X288391D01*
X311925Y370766D01*
Y366475D01*
G01X269561Y456044D02*
X274056D01*
X278400Y451700D01*
Y447097D01*
X284802Y440700D01*
X291000D01*
X292800Y438900D01*
Y435700D01*
X288300Y431200D01*
Y417798D01*
X304198Y401900D01*
X308926D01*
G01X295410Y179235D02*
X295400Y179245D01*
Y182227D01*
G03X295030Y182597I-370J0D01*
G01X293968D01*
G03X293598Y182227I0J-370D01*
G01Y181090D01*
G02X293228Y180720I-370J0D01*
G01X288804D01*
G03X288276Y180501I0J-746D01*
G01X286966Y179191D01*
G02X286633Y179053I-333J333D01*
G01X283704D01*
G02X283234Y179523I0J470D01*
G01Y180222D01*
G03X282638Y180818I-596J0D01*
G01X280663D01*
G03X279864Y180487I0J-1130D01*
G01X276754Y177377D01*
G03X276138Y175890I1487J-1487D01*
G01Y174735D01*
G02X276041Y174501I-331J0D01*
G01X275904Y174364D01*
G02X275670Y174267I-234J234D01*
G01X273644D01*
G54D19*
G01X264222Y176791D02*
X264706Y177275D01*
G03X265142Y178328I-1054J1053D01*
G01Y179502D01*
G03X264819Y180281I-1101J0D01*
G01X264500Y180600D01*
G03X264259Y180700I-241J-240D01*
G01X257829D01*
G02X256414Y181286I0J2001D01*
G01X256056Y181643D01*
G02X255470Y183059I1415J1415D01*
G01Y187237D01*
G02X257823Y189590I2353J0D01*
G01X259039D01*
G02X261121Y188727I0J-2943D01*
G01X263348Y186500D01*
G03X263589Y186400I241J240D01*
G01X270990D01*
G03X271120Y186427I-3J340D01*
G01X276156Y188512D01*
G02X276921Y188664I765J-1849D01*
G01X296497D01*
G02X297912Y188078I0J-2001D01*
G01X298244Y187746D01*
G02X298850Y186282I-1464J-1463D01*
G01Y179022D01*
G03X298950Y178781I340J0D01*
G01X299131Y178600D01*
G03X299372Y178500I241J240D01*
G01X300281D01*
G03X300522Y178600I0J340D01*
G01X300710Y178788D01*
G03X300810Y179029I-240J241D01*
G01Y181323D01*
G02X301734Y183553I3155J-1D01*
G01X302067Y183886D01*
G02X304126Y184740I2060J-2057D01*
G01X306930D01*
G03X307659Y185042I0J1031D01*
G01X308008Y185391D01*
G01X267722Y176791D02*
X267238Y177275D01*
G02X266802Y178328I1054J1053D01*
G01Y179503D01*
G03X265993Y181455I-2761J-1D01*
G01X265674Y181774D01*
G03X264259Y182360I-1415J-1415D01*
G01X262873D01*
G02X261670Y182858I0J1702D01*
G01X261285Y183243D01*
G03X260472Y183580I-813J-812D01*
G01X260404D01*
G03X259591Y183243I0J-1149D01*
G01X259045Y182697D01*
G02X258232Y182360I-813J812D01*
G01X257829D01*
G02X257588Y182460I0J340D01*
G01X257229Y182818D01*
G02X257131Y183058I242J239D01*
G01X257130D01*
Y187237D01*
G02X257823Y187930I693J0D01*
G01X259039D01*
G02X259946Y187553I-1J-1282D01*
G01X262173Y185326D01*
G03X263589Y184740I1415J1415D01*
G01X265685D01*
G02X266888Y184242I0J-1702D01*
G01X267273Y183857D01*
G03X268086Y183520I813J812D01*
G01X268154D01*
G03X268967Y183857I0J1149D01*
G01X269352Y184242D01*
G02X270555Y184740I1203J-1204D01*
G01X270990D01*
G03X271755Y184892I0J2001D01*
G01X272082Y185028D01*
G02X273346Y185027I631J-1527D01*
G01X273868Y184811D01*
G03X274749I441J1065D01*
G01X274814Y184838D01*
G03X275435Y185462I-447J1066D01*
G01X275730Y186174D01*
G02X276352Y186796I1061J-439D01*
G01X276792Y186978D01*
G02X276922Y187004I130J-314D01*
G01X281115D01*
G02X282318Y186506I0J-1702D01*
G01X282703Y186121D01*
G03X283516Y185784I813J812D01*
G01X283584D01*
G03X284397Y186121I0J1149D01*
G01X284782Y186506D01*
G02X285985Y187004I1203J-1204D01*
G01X296497D01*
G02X296738Y186904I0J-340D01*
G01X297070Y186572D01*
G02X297190Y186282I-290J-290D01*
G01Y179022D01*
G03X297776Y177607I2001J0D01*
G01X297957Y177426D01*
G03X299372Y176840I1415J1415D01*
G01X300281D01*
G03X301696Y177426I0J2001D01*
G01X301884Y177613D01*
G03X302470Y179029I-1415J1415D01*
G01Y181322D01*
G02X302908Y182379I1494J0D01*
G01X303242Y182713D01*
G02X304127Y183080I885J-884D01*
G01X306999D01*
G02X307781Y182756I0J-1106D01*
G01X308152Y182385D01*
G01X263580Y214593D02*
X264064Y215077D01*
G03X264499Y216125I-1054J1052D01*
G01X264500D01*
G02X265388Y217781I2001J-7D01*
G01X271872Y222115D01*
G02X272989Y222450I1109J-1667D01*
G01X297476D01*
G02X300336Y221265I0J-4044D01*
G01X305574Y216026D01*
G02X307460Y211473I-4553J-4553D01*
G01Y211439D01*
G03X307574Y211165I388J1D01*
G01X308008Y210731D01*
G01X267080Y214593D02*
X266415Y215258D01*
G02X266160Y215873I614J615D01*
G01Y216118D01*
G02X266311Y216401I341J0D01*
G01X272794Y220733D01*
G02X272984Y220790I189J-285D01*
G01X274735D01*
G02X275938Y220292I0J-1702D01*
G01X276323Y219907D01*
G03X277136Y219570I813J812D01*
G01X277204D01*
G03X278017Y219907I0J1149D01*
G01X278563Y220453D01*
G02X279376Y220790I813J-812D01*
G01X279444D01*
G02X280257Y220453I0J-1149D01*
G01X280803Y219907D01*
G03X281616Y219570I813J812D01*
G01X281684D01*
G03X282497Y219907I0J1149D01*
G01X283043Y220453D01*
G02X283856Y220790I813J-812D01*
G01X283924D01*
G02X284737Y220453I0J-1149D01*
G01X285283Y219907D01*
G03X286096Y219570I813J812D01*
G01X286164D01*
G03X286977Y219907I0J1149D01*
G01X287523Y220453D01*
G02X288336Y220790I813J-812D01*
G01X288404D01*
G02X289217Y220453I0J-1149D01*
G01X289763Y219907D01*
G03X290576Y219570I813J812D01*
G01X290644D01*
G03X291457Y219907I0J1149D01*
G01X291842Y220292D01*
G02X293045Y220790I1203J-1204D01*
G01X297476D01*
G02X299162Y220091I0J-2383D01*
G01X299279Y219973D01*
G02X299777Y218770I-1204J-1203D01*
G01Y218224D01*
G03X300114Y217411I1149J0D01*
G01X300161Y217364D01*
G03X300974Y217027I813J812D01*
G01X301520D01*
G02X302723Y216529I0J-1702D01*
G01X304400Y214852D01*
G02X305800Y211473I-3378J-3379D01*
G01Y211385D01*
X305002Y210587D01*
G01X451000Y-215000D02*
X447170D01*
X446830Y-214660D01*
Y-204618D01*
X445178Y-202966D01*
X418610D01*
X417930Y-202286D01*
Y-198806D01*
X418610Y-198126D01*
X474078D01*
X475730Y-196474D01*
Y-191618D01*
X474078Y-189966D01*
X418450D01*
X417770Y-189286D01*
Y-185806D01*
X418450Y-185126D01*
X474078D01*
X475730Y-183474D01*
Y-178618D01*
X474078Y-176966D01*
X417350D01*
X416670Y-176286D01*
Y-172806D01*
X417350Y-172126D01*
X474078D01*
X475730Y-170474D01*
Y-165618D01*
X474078Y-163966D01*
X417430D01*
X416750Y-163286D01*
Y-159806D01*
X417430Y-159126D01*
X474078D01*
X475730Y-157474D01*
Y-152618D01*
X474078Y-150966D01*
X417510D01*
X416830Y-150286D01*
Y-146806D01*
X417510Y-146126D01*
X445178D01*
X446830Y-144474D01*
Y-136940D01*
X447170Y-136600D01*
X451000D01*
G01X441000Y-215000D02*
X444830D01*
X445170Y-214660D01*
Y-205306D01*
X444490Y-204626D01*
X417922D01*
X416270Y-202974D01*
Y-198118D01*
X417922Y-196466D01*
X473390D01*
X474070Y-195786D01*
Y-192306D01*
X473390Y-191626D01*
X417762D01*
X416110Y-189974D01*
Y-185118D01*
X417762Y-183466D01*
X473390D01*
X474070Y-182786D01*
Y-179306D01*
X473390Y-178626D01*
X416662D01*
X415010Y-176974D01*
Y-172118D01*
X416662Y-170466D01*
X473390D01*
X474070Y-169786D01*
Y-166306D01*
X473390Y-165626D01*
X416742D01*
X415090Y-163974D01*
Y-159118D01*
X416742Y-157466D01*
X473390D01*
X474070Y-156786D01*
Y-153306D01*
X473390Y-152626D01*
X416822D01*
X415170Y-150974D01*
Y-146118D01*
X416822Y-144466D01*
X444490D01*
X445170Y-143786D01*
Y-136940D01*
X444830Y-136600D01*
X441000D01*
M02*
